G04 ================== begin FILE IDENTIFICATION RECORD ==================*
G04 Layout Name:  x887571-005_osp.brd*
G04 Film Name:    spt*
G04 File Format:  Gerber RS274X*
G04 File Origin:  Cadence Allegro 16.3-S036*
G04 Origin Date:  Thu Jul 03 00:06:57 2014*
G04 *
G04 Layer:  VIA CLASS/PASTEMASK_TOP*
G04 Layer:  PIN/PASTEMASK_TOP*
G04 Layer:  PACKAGE GEOMETRY/PASTEMASK_TOP*
G04 Layer:  DRAWING FORMAT/COMMON TEXT*
G04 Layer:  BOARD GEOMETRY/PASTEMASK_TOP*
G04 *
G04 Offset:    (0.0000 0.0000)*
G04 Mirror:    No*
G04 Mode:      Positive*
G04 Rotation:  0*
G04 FullContactRelief:  No*
G04 UndefLineWidth:     4.0000*
G04 ================== end FILE IDENTIFICATION RECORD ====================*
%FSLAX25Y25*MOIN*%
%IR0*IPPOS*OFA0.00000B0.00000*MIA0B0*SFA1.00000B1.00000*%
%ADD13R,.135X.05*%
%ADD11C,.025*%
%ADD16R,.023X.02*%
%ADD12R,.02X.023*%
%ADD15O,.014X.071*%
%ADD10R,.032X.028*%
%ADD17O,.02X.079*%
%ADD14R,.028X.032*%
%ADD18C,.01*%
%ADD19C,.012*%
%ADD20C,.013*%
%ADD21C,.015*%
%ADD22C,.004*%
%ADD23C,.005*%
%ADD24C,.006*%
%ADD25C,.007*%
%ADD26C,.008*%
G75*
%LPD*%
G75*
G54D10*
X-1519000Y-125359D03*
Y-120241D03*
X-1396100Y-136650D03*
Y-131550D03*
X-1356500Y-16041D03*
Y-21159D03*
X-1324500Y-16841D03*
Y-21959D03*
X-1316728Y-85900D03*
Y-80800D03*
X-1317700Y-69059D03*
Y-63941D03*
X-1113328Y-179209D03*
Y-174091D03*
X-1107828D03*
Y-179209D03*
X-1061900Y-38150D03*
X-1063928Y-53400D03*
Y-48300D03*
X-1061900Y-33050D03*
X-1062000Y-9450D03*
Y-14550D03*
X-948500Y-170441D03*
Y-175559D03*
X-649700Y-125359D03*
Y-120241D03*
X-535500Y-127350D03*
Y-122250D03*
X-486421Y-16041D03*
Y-21159D03*
X-448128Y-85800D03*
Y-80700D03*
X-449100Y-63841D03*
Y-68959D03*
X-454421Y-16841D03*
Y-21959D03*
X-243250Y-179209D03*
Y-174091D03*
X-237750D03*
Y-179209D03*
X-190100Y-38450D03*
X-192350Y-52900D03*
Y-47800D03*
X-190100Y-33350D03*
X-190400Y-8750D03*
Y-13850D03*
X-78400Y-171441D03*
Y-176559D03*
G54D20*
G01X-1183150Y-540000D02*
Y-552500D01*
G01X-1186485Y-540000D02*
X-1179815D01*
G01X-1171350Y-552500D02*
X-1172510Y-552292D01*
X-1173525Y-551459D01*
X-1174395Y-550208D01*
X-1174975Y-548750D01*
X-1175265Y-547083D01*
Y-545417D01*
X-1174975Y-543750D01*
X-1174395Y-542292D01*
X-1173525Y-541042D01*
X-1172510Y-540208D01*
X-1171350Y-540000D01*
X-1170190Y-540208D01*
X-1169175Y-541042D01*
X-1168305Y-542292D01*
X-1167725Y-543750D01*
X-1167435Y-545417D01*
Y-547083D01*
X-1167725Y-548750D01*
X-1168305Y-550208D01*
X-1169175Y-551459D01*
X-1170190Y-552292D01*
X-1171350Y-552500D01*
G01X-1162450D02*
Y-540000D01*
X-1158970D01*
X-1157810Y-540625D01*
X-1156940Y-542083D01*
X-1156650Y-543750D01*
X-1156940Y-545417D01*
X-1157665Y-546667D01*
X-1158970Y-547292D01*
X-1162450D01*
G01X-1138995Y-550834D02*
X-1137835Y-551875D01*
X-1136530Y-552500D01*
X-1135370D01*
X-1134210Y-551875D01*
X-1133340Y-550834D01*
X-1132905Y-549375D01*
X-1133195Y-547917D01*
X-1133920Y-546667D01*
X-1135225Y-545833D01*
X-1136965Y-545417D01*
X-1137980Y-544584D01*
X-1138415Y-543125D01*
X-1138125Y-541667D01*
X-1137400Y-540625D01*
X-1136385Y-540000D01*
X-1135370D01*
X-1134355Y-540417D01*
X-1133485Y-541458D01*
G01X-1125890Y-540000D02*
X-1122410D01*
G01X-1124150D02*
Y-552500D01*
G01X-1125890D02*
X-1122410D01*
G01X-1115540D02*
Y-540000D01*
X-1112640D01*
X-1111480Y-540625D01*
X-1110610Y-541458D01*
X-1109885Y-542708D01*
X-1109305Y-544167D01*
X-1109160Y-546250D01*
X-1109305Y-548333D01*
X-1109885Y-549792D01*
X-1110610Y-551042D01*
X-1111480Y-551875D01*
X-1112640Y-552500D01*
X-1115540D01*
G01X-1097650D02*
X-1103450D01*
Y-540000D01*
X-1097650D01*
G01X-1099970Y-546042D02*
X-1103450D01*
G01X-1079995Y-550834D02*
X-1078835Y-551875D01*
X-1077530Y-552500D01*
X-1076370D01*
X-1075210Y-551875D01*
X-1074340Y-550834D01*
X-1073905Y-549375D01*
X-1074195Y-547917D01*
X-1074920Y-546667D01*
X-1076225Y-545833D01*
X-1077965Y-545417D01*
X-1078980Y-544584D01*
X-1079415Y-543125D01*
X-1079125Y-541667D01*
X-1078400Y-540625D01*
X-1077385Y-540000D01*
X-1076370D01*
X-1075355Y-540417D01*
X-1074485Y-541458D01*
G01X-1065150Y-552500D02*
X-1066310Y-552292D01*
X-1067325Y-551459D01*
X-1068195Y-550208D01*
X-1068775Y-548750D01*
X-1069065Y-547083D01*
Y-545417D01*
X-1068775Y-543750D01*
X-1068195Y-542292D01*
X-1067325Y-541042D01*
X-1066310Y-540208D01*
X-1065150Y-540000D01*
X-1063990Y-540208D01*
X-1062975Y-541042D01*
X-1062105Y-542292D01*
X-1061525Y-543750D01*
X-1061235Y-545417D01*
Y-547083D01*
X-1061525Y-548750D01*
X-1062105Y-550208D01*
X-1062975Y-551459D01*
X-1063990Y-552292D01*
X-1065150Y-552500D01*
G01X-1056250Y-540000D02*
Y-552500D01*
X-1050450D01*
G01X-1044740D02*
Y-540000D01*
X-1041840D01*
X-1040680Y-540625D01*
X-1039810Y-541458D01*
X-1039085Y-542708D01*
X-1038505Y-544167D01*
X-1038360Y-546250D01*
X-1038505Y-548333D01*
X-1039085Y-549792D01*
X-1039810Y-551042D01*
X-1040680Y-551875D01*
X-1041840Y-552500D01*
X-1044740D01*
G01X-1026850D02*
X-1032650D01*
Y-540000D01*
X-1026850D01*
G01X-1029170Y-546042D02*
X-1032650D01*
G01X-1020850Y-552500D02*
Y-540000D01*
X-1017225D01*
X-1016065Y-540625D01*
X-1015340Y-541458D01*
X-1015050Y-543125D01*
X-1015340Y-544792D01*
X-1016210Y-545833D01*
X-1017225Y-546458D01*
X-1020850D01*
G01X-1017225D02*
X-1015050Y-552500D01*
G01X-1009050D02*
Y-540000D01*
X-1005570D01*
X-1004410Y-540625D01*
X-1003540Y-542083D01*
X-1003250Y-543750D01*
X-1003540Y-545417D01*
X-1004265Y-546667D01*
X-1005570Y-547292D01*
X-1009050D01*
G01X-997975Y-552500D02*
X-994350Y-540000D01*
X-990725Y-552500D01*
G01X-992030Y-548125D02*
X-996670D01*
G01X-985595Y-550834D02*
X-984435Y-551875D01*
X-983130Y-552500D01*
X-981970D01*
X-980810Y-551875D01*
X-979940Y-550834D01*
X-979505Y-549375D01*
X-979795Y-547917D01*
X-980520Y-546667D01*
X-981825Y-545833D01*
X-983565Y-545417D01*
X-984580Y-544584D01*
X-985015Y-543125D01*
X-984725Y-541667D01*
X-984000Y-540625D01*
X-982985Y-540000D01*
X-981970D01*
X-980955Y-540417D01*
X-980085Y-541458D01*
G01X-970750Y-540000D02*
Y-552500D01*
G01X-974085Y-540000D02*
X-967415D01*
G01X-956050Y-552500D02*
X-961850D01*
Y-540000D01*
X-956050D01*
G01X-958370Y-546042D02*
X-961850D01*
G54D11*
X-1484193Y-164390D03*
Y-169390D03*
X-1489193Y-164390D03*
Y-169390D03*
X-1494193Y-164390D03*
Y-169390D03*
X-1484193Y-149390D03*
Y-154390D03*
Y-159390D03*
X-1489193Y-149390D03*
Y-154390D03*
Y-159390D03*
X-1494193Y-149390D03*
Y-154390D03*
Y-159390D03*
X-1484193Y-134390D03*
Y-139390D03*
Y-144390D03*
X-1489193Y-134390D03*
Y-139390D03*
Y-144390D03*
X-1494193Y-134390D03*
Y-139390D03*
Y-144390D03*
X-1484193Y-119390D03*
Y-124390D03*
Y-129390D03*
X-1489193Y-119390D03*
Y-124390D03*
Y-129390D03*
X-1494193Y-119390D03*
Y-124390D03*
Y-129390D03*
X-1484193Y-104390D03*
Y-109390D03*
Y-114390D03*
X-1489193Y-104390D03*
Y-109390D03*
Y-114390D03*
X-1494193Y-104390D03*
Y-109390D03*
Y-114390D03*
X-1484193Y-89390D03*
Y-94390D03*
Y-99390D03*
X-1489193Y-89390D03*
Y-94390D03*
Y-99390D03*
X-1494193Y-89390D03*
Y-94390D03*
Y-99390D03*
X-1484193Y-74390D03*
Y-79390D03*
Y-84390D03*
X-1489193Y-74390D03*
Y-79390D03*
Y-84390D03*
X-1494193Y-74390D03*
Y-79390D03*
Y-84390D03*
X-1469193Y-164390D03*
Y-169390D03*
X-1474193Y-164390D03*
Y-169390D03*
X-1479193Y-164390D03*
Y-169390D03*
X-1469193Y-149390D03*
Y-154390D03*
Y-159390D03*
X-1474193Y-149390D03*
Y-154390D03*
Y-159390D03*
X-1479193Y-149390D03*
Y-154390D03*
Y-159390D03*
X-1469193Y-134390D03*
Y-139390D03*
Y-144390D03*
X-1474193Y-134390D03*
Y-139390D03*
Y-144390D03*
X-1479193Y-134390D03*
Y-139390D03*
Y-144390D03*
X-1469193Y-119390D03*
Y-124390D03*
Y-129390D03*
X-1474193Y-119390D03*
Y-124390D03*
Y-129390D03*
X-1479193Y-119390D03*
Y-124390D03*
Y-129390D03*
X-1469193Y-104390D03*
Y-109390D03*
Y-114390D03*
X-1474193Y-104390D03*
Y-109390D03*
Y-114390D03*
X-1479193Y-104390D03*
Y-109390D03*
Y-114390D03*
X-1469193Y-89390D03*
Y-94390D03*
Y-99390D03*
X-1474193Y-89390D03*
Y-94390D03*
Y-99390D03*
X-1479193Y-89390D03*
Y-94390D03*
Y-99390D03*
X-1469193Y-74390D03*
Y-79390D03*
Y-84390D03*
X-1474193Y-74390D03*
Y-79390D03*
Y-84390D03*
X-1479193Y-74390D03*
Y-79390D03*
Y-84390D03*
X-1459193Y-164390D03*
Y-169390D03*
X-1464193Y-164390D03*
Y-169390D03*
X-1459193Y-149390D03*
Y-154390D03*
Y-159390D03*
X-1464193Y-149390D03*
Y-154390D03*
Y-159390D03*
X-1459193Y-134390D03*
Y-139390D03*
Y-144390D03*
X-1464193Y-134390D03*
Y-139390D03*
Y-144390D03*
X-1459193Y-119390D03*
Y-124390D03*
Y-129390D03*
X-1464193Y-119390D03*
Y-124390D03*
Y-129390D03*
X-1459193Y-104390D03*
Y-109390D03*
Y-114390D03*
X-1464193Y-104390D03*
Y-109390D03*
Y-114390D03*
X-1459193Y-89390D03*
Y-94390D03*
Y-99390D03*
X-1464193Y-89390D03*
Y-94390D03*
Y-99390D03*
X-1459193Y-74390D03*
Y-79390D03*
Y-84390D03*
X-1464193Y-74390D03*
Y-79390D03*
Y-84390D03*
X-619114Y-164390D03*
Y-169390D03*
X-624114Y-164390D03*
Y-169390D03*
X-619114Y-149390D03*
Y-154390D03*
Y-159390D03*
X-624114Y-149390D03*
Y-154390D03*
Y-159390D03*
X-619114Y-134390D03*
Y-139390D03*
Y-144390D03*
X-624114Y-134390D03*
Y-139390D03*
Y-144390D03*
X-619114Y-119390D03*
Y-124390D03*
Y-129390D03*
X-624114Y-119390D03*
Y-124390D03*
Y-129390D03*
X-619114Y-104390D03*
Y-109390D03*
Y-114390D03*
X-624114Y-104390D03*
Y-109390D03*
Y-114390D03*
X-619114Y-89390D03*
Y-94390D03*
Y-99390D03*
X-624114Y-89390D03*
Y-94390D03*
Y-99390D03*
X-619114Y-74390D03*
Y-79390D03*
Y-84390D03*
X-624114Y-74390D03*
Y-79390D03*
Y-84390D03*
X-604114Y-164390D03*
Y-169390D03*
X-609114Y-164390D03*
Y-169390D03*
X-614114Y-164390D03*
Y-169390D03*
X-604114Y-149390D03*
Y-154390D03*
Y-159390D03*
X-609114Y-149390D03*
Y-154390D03*
Y-159390D03*
X-614114Y-149390D03*
Y-154390D03*
Y-159390D03*
X-604114Y-134390D03*
Y-139390D03*
Y-144390D03*
X-609114Y-134390D03*
Y-139390D03*
Y-144390D03*
X-614114Y-134390D03*
Y-139390D03*
Y-144390D03*
X-604114Y-119390D03*
Y-124390D03*
Y-129390D03*
X-609114Y-119390D03*
Y-124390D03*
Y-129390D03*
X-614114Y-119390D03*
Y-124390D03*
Y-129390D03*
X-604114Y-104390D03*
Y-109390D03*
Y-114390D03*
X-609114Y-104390D03*
Y-109390D03*
Y-114390D03*
X-614114Y-104390D03*
Y-109390D03*
Y-114390D03*
X-604114Y-89390D03*
Y-94390D03*
Y-99390D03*
X-609114Y-89390D03*
Y-94390D03*
Y-99390D03*
X-614114Y-89390D03*
Y-94390D03*
Y-99390D03*
X-604114Y-74390D03*
Y-79390D03*
Y-84390D03*
X-609114Y-74390D03*
Y-79390D03*
Y-84390D03*
X-614114Y-74390D03*
Y-79390D03*
Y-84390D03*
X-589114Y-164390D03*
Y-169390D03*
X-594114Y-164390D03*
Y-169390D03*
X-599114Y-164390D03*
Y-169390D03*
X-589114Y-149390D03*
Y-154390D03*
Y-159390D03*
X-594114Y-149390D03*
Y-154390D03*
Y-159390D03*
X-599114Y-149390D03*
Y-154390D03*
Y-159390D03*
X-589114Y-134390D03*
Y-139390D03*
Y-144390D03*
X-594114Y-134390D03*
Y-139390D03*
Y-144390D03*
X-599114Y-134390D03*
Y-139390D03*
Y-144390D03*
X-589114Y-119390D03*
Y-124390D03*
Y-129390D03*
X-594114Y-119390D03*
Y-124390D03*
Y-129390D03*
X-599114Y-119390D03*
Y-124390D03*
Y-129390D03*
X-589114Y-104390D03*
Y-109390D03*
Y-114390D03*
X-594114Y-104390D03*
Y-109390D03*
Y-114390D03*
X-599114Y-104390D03*
Y-109390D03*
Y-114390D03*
X-589114Y-89390D03*
Y-94390D03*
Y-99390D03*
X-594114Y-89390D03*
Y-94390D03*
Y-99390D03*
X-599114Y-89390D03*
Y-94390D03*
Y-99390D03*
X-589114Y-74390D03*
Y-79390D03*
Y-84390D03*
X-594114Y-74390D03*
Y-79390D03*
Y-84390D03*
X-599114Y-74390D03*
Y-79390D03*
Y-84390D03*
G54D21*
G01X-1185925Y-592500D02*
X-1178575Y-577500D01*
G01X-1185925D02*
X-1178575Y-592500D01*
G01X-1168050D02*
X-1166825Y-592250D01*
X-1165425Y-591500D01*
X-1164550Y-590250D01*
X-1164200Y-588500D01*
X-1164550Y-586750D01*
X-1165600Y-585250D01*
X-1167175Y-584500D01*
X-1168925D01*
X-1169975Y-584000D01*
X-1170850Y-582750D01*
X-1171200Y-581000D01*
X-1170675Y-579250D01*
X-1169450Y-578000D01*
X-1168050Y-577500D01*
X-1166650Y-578000D01*
X-1165425Y-579250D01*
X-1164900Y-581000D01*
X-1165250Y-582750D01*
X-1166125Y-584000D01*
X-1167175Y-584500D01*
X-1168925D01*
X-1170500Y-585250D01*
X-1171550Y-586750D01*
X-1171900Y-588500D01*
X-1171550Y-590250D01*
X-1170675Y-591500D01*
X-1169275Y-592250D01*
X-1168050Y-592500D01*
G01X-1153850D02*
X-1152625Y-592250D01*
X-1151225Y-591500D01*
X-1150350Y-590250D01*
X-1150000Y-588500D01*
X-1150350Y-586750D01*
X-1151400Y-585250D01*
X-1152975Y-584500D01*
X-1154725D01*
X-1155775Y-584000D01*
X-1156650Y-582750D01*
X-1157000Y-581000D01*
X-1156475Y-579250D01*
X-1155250Y-578000D01*
X-1153850Y-577500D01*
X-1152450Y-578000D01*
X-1151225Y-579250D01*
X-1150700Y-581000D01*
X-1151050Y-582750D01*
X-1151925Y-584000D01*
X-1152975Y-584500D01*
X-1154725D01*
X-1156300Y-585250D01*
X-1157350Y-586750D01*
X-1157700Y-588500D01*
X-1157350Y-590250D01*
X-1156475Y-591500D01*
X-1155075Y-592250D01*
X-1153850Y-592500D01*
G01X-1140000D02*
X-1139650Y-589250D01*
X-1139125Y-586500D01*
X-1138425Y-584000D01*
X-1137550Y-581250D01*
X-1136150Y-577500D01*
X-1143150D01*
G01X-1129300Y-590250D02*
X-1128250Y-591500D01*
X-1127025Y-592250D01*
X-1125450Y-592500D01*
X-1123875Y-592000D01*
X-1122650Y-591000D01*
X-1121775Y-589250D01*
X-1121600Y-587250D01*
X-1121950Y-585250D01*
X-1122825Y-584000D01*
X-1124050Y-583000D01*
X-1125275Y-582750D01*
X-1126500Y-583000D01*
X-1128075Y-584000D01*
X-1127550Y-577500D01*
X-1122825D01*
G01X-1111600Y-592500D02*
X-1111250Y-589250D01*
X-1110725Y-586500D01*
X-1110025Y-584000D01*
X-1109150Y-581250D01*
X-1107750Y-577500D01*
X-1114750D01*
G01X-1097050Y-592500D02*
Y-577500D01*
X-1099150Y-580500D01*
G01Y-592500D02*
X-1094950D01*
G01X-1085125Y-587500D02*
X-1080575D01*
G01X-1068650Y-577500D02*
X-1070050Y-578000D01*
X-1071100Y-579250D01*
X-1071800Y-580750D01*
X-1072325Y-582750D01*
X-1072500Y-585000D01*
X-1072325Y-587250D01*
X-1071800Y-589250D01*
X-1071100Y-590750D01*
X-1070050Y-592000D01*
X-1068650Y-592500D01*
X-1067250Y-592000D01*
X-1066200Y-590750D01*
X-1065500Y-589250D01*
X-1064975Y-587250D01*
X-1064800Y-585000D01*
X-1064975Y-582750D01*
X-1065500Y-580750D01*
X-1066200Y-579250D01*
X-1067250Y-578000D01*
X-1068650Y-577500D01*
G01X-1054450D02*
X-1055850Y-578000D01*
X-1056900Y-579250D01*
X-1057600Y-580750D01*
X-1058125Y-582750D01*
X-1058300Y-585000D01*
X-1058125Y-587250D01*
X-1057600Y-589250D01*
X-1056900Y-590750D01*
X-1055850Y-592000D01*
X-1054450Y-592500D01*
X-1053050Y-592000D01*
X-1052000Y-590750D01*
X-1051300Y-589250D01*
X-1050775Y-587250D01*
X-1050600Y-585000D01*
X-1050775Y-582750D01*
X-1051300Y-580750D01*
X-1052000Y-579250D01*
X-1053050Y-578000D01*
X-1054450Y-577500D01*
G01X-1044100Y-590250D02*
X-1043050Y-591500D01*
X-1041825Y-592250D01*
X-1040250Y-592500D01*
X-1038675Y-592000D01*
X-1037450Y-591000D01*
X-1036575Y-589250D01*
X-1036400Y-587250D01*
X-1036750Y-585250D01*
X-1037625Y-584000D01*
X-1038850Y-583000D01*
X-1040075Y-582750D01*
X-1041300Y-583000D01*
X-1042875Y-584000D01*
X-1042350Y-577500D01*
X-1037625D01*
G01X-911875Y-592500D02*
X-907500Y-577500D01*
X-903125Y-592500D01*
G01X-904700Y-587250D02*
X-910300D01*
G54D12*
X-1391300Y-133200D03*
Y-136800D03*
X-1322228Y-85650D03*
Y-82050D03*
X-1059228Y-49050D03*
Y-52650D03*
X-1054228Y-44050D03*
Y-47650D03*
X-1048000Y-47611D03*
Y-43989D03*
X-1056000Y-37300D03*
Y-33700D03*
Y-13300D03*
Y-9700D03*
X-519200Y-123700D03*
Y-127300D03*
X-453628Y-85550D03*
Y-81950D03*
X-187650Y-48550D03*
Y-52150D03*
X-182650Y-43550D03*
Y-47150D03*
X-177150Y-47161D03*
Y-43539D03*
X-184150Y-38150D03*
Y-34550D03*
Y-12650D03*
Y-9050D03*
G54D22*
G01X-1200000Y-560000D02*
X-890000D01*
G01Y-520000D02*
X-1200000D01*
G01X-575000Y-480000D02*
X-1200000D01*
G01X-927500Y-560000D02*
Y-600000D01*
G01X-915000Y-440000D02*
Y-480000D01*
G01X-890000D02*
Y-600000D01*
G01X-870000Y-440000D02*
Y-480000D01*
G01X-680000D02*
Y-440000D01*
G01X-1200000Y-600000D02*
X-575000D01*
Y-440000D01*
X-1200000D01*
Y-600000D01*
G54D13*
X-1341850Y-16000D03*
X-1330350Y-6000D03*
X-1311050Y-16900D03*
X-1299550Y-6900D03*
X-471771Y-16000D03*
X-460271Y-6000D03*
X-440971Y-16900D03*
X-429471Y-6900D03*
G54D23*
G01X-1007500Y-470000D02*
X-1006450Y-475000D01*
X-1005250Y-470000D01*
X-1004050Y-475000D01*
X-1003000Y-470000D01*
G01X-1001125Y-475000D02*
X-999250Y-470000D01*
X-997375Y-475000D01*
G01X-998050Y-473250D02*
X-1000450D01*
G01X-994825Y-474333D02*
X-994225Y-474750D01*
X-993550Y-475000D01*
X-992950D01*
X-992350Y-474750D01*
X-991900Y-474333D01*
X-991675Y-473750D01*
X-991825Y-473167D01*
X-992200Y-472667D01*
X-992875Y-472333D01*
X-993775Y-472167D01*
X-994300Y-471833D01*
X-994525Y-471250D01*
X-994375Y-470667D01*
X-994000Y-470250D01*
X-993475Y-470000D01*
X-992950D01*
X-992425Y-470167D01*
X-991975Y-470583D01*
G01X-988825Y-475000D02*
Y-470000D01*
G01X-985675D02*
Y-475000D01*
G01Y-472500D02*
X-988825D01*
G01X-976525Y-474417D02*
X-976000Y-474833D01*
X-975400Y-475000D01*
X-974800Y-474833D01*
X-974275Y-474333D01*
X-973900Y-473583D01*
X-973750Y-472833D01*
Y-471917D01*
X-973900Y-471167D01*
X-974275Y-470500D01*
X-974725Y-470167D01*
X-975250Y-470000D01*
X-975850Y-470167D01*
X-976300Y-470500D01*
X-976600Y-471000D01*
X-976750Y-471667D01*
X-976600Y-472250D01*
X-976225Y-472833D01*
X-975775Y-473167D01*
X-975250Y-473250D01*
X-974650Y-473083D01*
X-974200Y-472667D01*
X-973750Y-471917D01*
G01X-969250Y-475000D02*
X-968725Y-474917D01*
X-968125Y-474667D01*
X-967750Y-474250D01*
X-967600Y-473667D01*
X-967750Y-473083D01*
X-968200Y-472583D01*
X-968875Y-472333D01*
X-969625D01*
X-970075Y-472167D01*
X-970450Y-471750D01*
X-970600Y-471167D01*
X-970375Y-470583D01*
X-969850Y-470167D01*
X-969250Y-470000D01*
X-968650Y-470167D01*
X-968125Y-470583D01*
X-967900Y-471167D01*
X-968050Y-471750D01*
X-968425Y-472167D01*
X-968875Y-472333D01*
X-969625D01*
X-970300Y-472583D01*
X-970750Y-473083D01*
X-970900Y-473667D01*
X-970750Y-474250D01*
X-970375Y-474667D01*
X-969775Y-474917D01*
X-969250Y-475000D01*
G01X-963250Y-470000D02*
X-963850Y-470167D01*
X-964300Y-470583D01*
X-964600Y-471083D01*
X-964825Y-471750D01*
X-964900Y-472500D01*
X-964825Y-473250D01*
X-964600Y-473917D01*
X-964300Y-474417D01*
X-963850Y-474833D01*
X-963250Y-475000D01*
X-962650Y-474833D01*
X-962200Y-474417D01*
X-961900Y-473917D01*
X-961675Y-473250D01*
X-961600Y-472500D01*
X-961675Y-471750D01*
X-961900Y-471083D01*
X-962200Y-470583D01*
X-962650Y-470167D01*
X-963250Y-470000D01*
G01X-958900Y-474250D02*
X-958450Y-474667D01*
X-957925Y-474917D01*
X-957250Y-475000D01*
X-956575Y-474833D01*
X-956050Y-474500D01*
X-955675Y-473917D01*
X-955600Y-473250D01*
X-955750Y-472583D01*
X-956125Y-472167D01*
X-956650Y-471833D01*
X-957175Y-471750D01*
X-957700Y-471833D01*
X-958375Y-472167D01*
X-958150Y-470000D01*
X-956125D01*
G01X-952675Y-470833D02*
X-952225Y-470333D01*
X-951700Y-470083D01*
X-951100Y-470000D01*
X-950350Y-470167D01*
X-949825Y-470583D01*
X-949675Y-471083D01*
X-949750Y-471583D01*
X-950050Y-472000D01*
X-951550Y-472833D01*
X-952225Y-473417D01*
X-952675Y-474250D01*
X-952825Y-475000D01*
X-949675D01*
G01X-946225Y-473333D02*
X-944275D01*
G01X-940675Y-472917D02*
X-940150Y-472333D01*
X-939700Y-472000D01*
X-939100Y-471833D01*
X-938575Y-472000D01*
X-938200Y-472333D01*
X-937900Y-472833D01*
X-937825Y-473417D01*
X-937900Y-473917D01*
X-938200Y-474417D01*
X-938650Y-474833D01*
X-939175Y-475000D01*
X-939775Y-474833D01*
X-940300Y-474333D01*
X-940600Y-473583D01*
X-940675Y-472750D01*
X-940525Y-471667D01*
X-940300Y-471083D01*
X-939925Y-470500D01*
X-939400Y-470083D01*
X-938875Y-470000D01*
X-938350Y-470167D01*
X-937975Y-470583D01*
G01X-934900Y-474000D02*
X-934450Y-474583D01*
X-933850Y-474917D01*
X-933175Y-475000D01*
X-932575Y-474917D01*
X-931975Y-474500D01*
X-931600Y-474000D01*
X-931525Y-473500D01*
X-931675Y-472917D01*
X-932200Y-472500D01*
X-932725Y-472333D01*
X-933400D01*
G01X-932725D02*
X-932275Y-472083D01*
X-931900Y-471667D01*
X-931750Y-471167D01*
X-931900Y-470667D01*
X-932275Y-470250D01*
X-932950Y-470000D01*
X-933625Y-470083D01*
X-934300Y-470417D01*
G01X-928525Y-474417D02*
X-928000Y-474833D01*
X-927400Y-475000D01*
X-926800Y-474833D01*
X-926275Y-474333D01*
X-925900Y-473583D01*
X-925750Y-472833D01*
Y-471917D01*
X-925900Y-471167D01*
X-926275Y-470500D01*
X-926725Y-470167D01*
X-927250Y-470000D01*
X-927850Y-470167D01*
X-928300Y-470500D01*
X-928600Y-471000D01*
X-928750Y-471667D01*
X-928600Y-472250D01*
X-928225Y-472833D01*
X-927775Y-473167D01*
X-927250Y-473250D01*
X-926650Y-473083D01*
X-926200Y-472667D01*
X-925750Y-471917D01*
G01X-922525Y-474417D02*
X-922000Y-474833D01*
X-921400Y-475000D01*
X-920800Y-474833D01*
X-920275Y-474333D01*
X-919900Y-473583D01*
X-919750Y-472833D01*
Y-471917D01*
X-919900Y-471167D01*
X-920275Y-470500D01*
X-920725Y-470167D01*
X-921250Y-470000D01*
X-921850Y-470167D01*
X-922300Y-470500D01*
X-922600Y-471000D01*
X-922750Y-471667D01*
X-922600Y-472250D01*
X-922225Y-472833D01*
X-921775Y-473167D01*
X-921250Y-473250D01*
X-920650Y-473083D01*
X-920200Y-472667D01*
X-919750Y-471917D01*
G01X-1006750Y-465000D02*
Y-460000D01*
X-1004875D01*
X-1004275Y-460250D01*
X-1003900Y-460583D01*
X-1003750Y-461250D01*
X-1003900Y-461917D01*
X-1004350Y-462333D01*
X-1004875Y-462583D01*
X-1006750D01*
G01X-1004875D02*
X-1003750Y-465000D01*
G01X-997750D02*
X-1000750D01*
Y-460000D01*
X-997750D01*
G01X-998950Y-462417D02*
X-1000750D01*
G01X-994900Y-465000D02*
Y-460000D01*
X-993400D01*
X-992800Y-460250D01*
X-992350Y-460583D01*
X-991975Y-461083D01*
X-991675Y-461667D01*
X-991600Y-462500D01*
X-991675Y-463333D01*
X-991975Y-463917D01*
X-992350Y-464417D01*
X-992800Y-464750D01*
X-993400Y-465000D01*
X-994900D01*
G01X-989200D02*
Y-460000D01*
X-987250Y-464167D01*
X-985300Y-460000D01*
Y-465000D01*
G01X-981250D02*
X-981850Y-464917D01*
X-982375Y-464583D01*
X-982825Y-464083D01*
X-983125Y-463500D01*
X-983275Y-462833D01*
Y-462167D01*
X-983125Y-461500D01*
X-982825Y-460917D01*
X-982375Y-460417D01*
X-981850Y-460083D01*
X-981250Y-460000D01*
X-980650Y-460083D01*
X-980125Y-460417D01*
X-979675Y-460917D01*
X-979375Y-461500D01*
X-979225Y-462167D01*
Y-462833D01*
X-979375Y-463500D01*
X-979675Y-464083D01*
X-980125Y-464583D01*
X-980650Y-464917D01*
X-981250Y-465000D01*
G01X-976975D02*
Y-460000D01*
X-973525Y-465000D01*
Y-460000D01*
G01X-970900Y-465000D02*
Y-460000D01*
X-969400D01*
X-968800Y-460250D01*
X-968350Y-460583D01*
X-967975Y-461083D01*
X-967675Y-461667D01*
X-967600Y-462500D01*
X-967675Y-463333D01*
X-967975Y-463917D01*
X-968350Y-464417D01*
X-968800Y-464750D01*
X-969400Y-465000D01*
X-970900D01*
G01X-1005250Y-455000D02*
Y-450000D01*
X-1006150Y-451000D01*
G01Y-455000D02*
X-1004350D01*
G01X-995200D02*
Y-450000D01*
X-993250Y-454167D01*
X-991300Y-450000D01*
Y-455000D01*
G01X-988150Y-450000D02*
X-986350D01*
G01X-987250D02*
Y-455000D01*
G01X-988150D02*
X-986350D01*
G01X-979600Y-450417D02*
X-980050Y-450167D01*
X-980575Y-450000D01*
X-981175D01*
X-981850Y-450250D01*
X-982375Y-450667D01*
X-982750Y-451167D01*
X-983050Y-452000D01*
X-983125Y-452750D01*
X-982975Y-453500D01*
X-982750Y-454000D01*
X-982300Y-454500D01*
X-981775Y-454833D01*
X-981250Y-455000D01*
X-980725D01*
X-980200Y-454833D01*
X-979750Y-454583D01*
X-979375Y-454250D01*
G01X-976750Y-455000D02*
Y-450000D01*
X-974875D01*
X-974275Y-450250D01*
X-973900Y-450583D01*
X-973750Y-451250D01*
X-973900Y-451917D01*
X-974350Y-452333D01*
X-974875Y-452583D01*
X-976750D01*
G01X-974875D02*
X-973750Y-455000D01*
G01X-969250D02*
X-969850Y-454917D01*
X-970375Y-454583D01*
X-970825Y-454083D01*
X-971125Y-453500D01*
X-971275Y-452833D01*
Y-452167D01*
X-971125Y-451500D01*
X-970825Y-450917D01*
X-970375Y-450417D01*
X-969850Y-450083D01*
X-969250Y-450000D01*
X-968650Y-450083D01*
X-968125Y-450417D01*
X-967675Y-450917D01*
X-967375Y-451500D01*
X-967225Y-452167D01*
Y-452833D01*
X-967375Y-453500D01*
X-967675Y-454083D01*
X-968125Y-454583D01*
X-968650Y-454917D01*
X-969250Y-455000D01*
G01X-964825Y-454333D02*
X-964225Y-454750D01*
X-963550Y-455000D01*
X-962950D01*
X-962350Y-454750D01*
X-961900Y-454333D01*
X-961675Y-453750D01*
X-961825Y-453167D01*
X-962200Y-452667D01*
X-962875Y-452333D01*
X-963775Y-452167D01*
X-964300Y-451833D01*
X-964525Y-451250D01*
X-964375Y-450667D01*
X-964000Y-450250D01*
X-963475Y-450000D01*
X-962950D01*
X-962425Y-450167D01*
X-961975Y-450583D01*
G01X-957250Y-455000D02*
X-957850Y-454917D01*
X-958375Y-454583D01*
X-958825Y-454083D01*
X-959125Y-453500D01*
X-959275Y-452833D01*
Y-452167D01*
X-959125Y-451500D01*
X-958825Y-450917D01*
X-958375Y-450417D01*
X-957850Y-450083D01*
X-957250Y-450000D01*
X-956650Y-450083D01*
X-956125Y-450417D01*
X-955675Y-450917D01*
X-955375Y-451500D01*
X-955225Y-452167D01*
Y-452833D01*
X-955375Y-453500D01*
X-955675Y-454083D01*
X-956125Y-454583D01*
X-956650Y-454917D01*
X-957250Y-455000D01*
G01X-952675D02*
Y-450000D01*
X-949825D01*
G01X-950875Y-452417D02*
X-952675D01*
G01X-945250Y-450000D02*
Y-455000D01*
G01X-946975Y-450000D02*
X-943525D01*
G01X-935500D02*
X-934450Y-455000D01*
X-933250Y-450000D01*
X-932050Y-455000D01*
X-931000Y-450000D01*
G01X-929125Y-455000D02*
X-927250Y-450000D01*
X-925375Y-455000D01*
G01X-926050Y-453250D02*
X-928450D01*
G01X-921250Y-455000D02*
Y-452750D01*
X-922750Y-450000D01*
G01X-919750D02*
X-921250Y-452750D01*
G54D14*
X-1302441Y-79700D03*
X-1307559D03*
Y-74200D03*
X-1302441D03*
Y-68700D03*
X-1307559D03*
Y-63200D03*
X-1302441D03*
X-1307559Y-57700D03*
X-1302441D03*
X-1307559Y-52200D03*
X-1302441D03*
X-1307559Y-41200D03*
X-1302441D03*
Y-46700D03*
X-1307559D03*
Y-30200D03*
X-1302441D03*
X-1307559Y-35700D03*
X-1302441D03*
X-1187559Y-40500D03*
X-1182441D03*
X-1187559Y-46500D03*
X-1182441D03*
X-1187359Y-29400D03*
X-1187487Y-23450D03*
X-1182369D03*
X-1187359Y-34900D03*
X-1182369Y-18250D03*
X-1187487D03*
X-1187409Y-12128D03*
X-1182291D03*
X-1187359Y-5800D03*
Y0D03*
X-1168559Y-38500D03*
Y-49500D03*
Y-44000D03*
Y-33000D03*
X-1182241Y-29400D03*
X-1168487Y-26950D03*
X-1182241Y-34900D03*
X-1168487Y-10750D03*
Y-21750D03*
Y-16250D03*
X-1182241Y-5800D03*
X-1168487Y-5450D03*
X-1182241Y0D03*
X-1163441Y-38500D03*
Y-49500D03*
Y-44000D03*
Y-33000D03*
X-1163369Y-26950D03*
Y-10750D03*
Y-21750D03*
Y-16250D03*
Y-5450D03*
X-1053787Y-52850D03*
X-1048669D03*
X-1045441Y-34000D03*
X-1050559D03*
X-1045441Y-10000D03*
X-1050559D03*
X-1045550Y-16600D03*
X-1050650D03*
X-438959Y-74100D03*
X-433841D03*
Y-79600D03*
X-438959D03*
X-433841Y-68600D03*
X-438959D03*
Y-63100D03*
X-433841D03*
X-438959Y-57600D03*
X-433841D03*
X-438959Y-46600D03*
X-433841D03*
X-438959Y-52100D03*
X-433841D03*
X-438959Y-41100D03*
X-433841D03*
X-438959Y-35600D03*
X-433841D03*
Y-29500D03*
X-438959D03*
X-318059Y-42000D03*
Y-47500D03*
X-317859Y-36400D03*
X-317987Y-24950D03*
X-317859Y-30900D03*
X-317987Y-19750D03*
X-317859Y-7300D03*
X-317909Y-13628D03*
X-317859Y-1500D03*
X-312941Y-42000D03*
Y-47500D03*
X-312741Y-36400D03*
X-312869Y-24950D03*
X-312741Y-30900D03*
X-312869Y-19750D03*
X-312741Y-7300D03*
X-312791Y-13628D03*
X-312741Y-1500D03*
X-299259Y-38000D03*
X-294141D03*
Y-48800D03*
X-299259D03*
X-294141Y-43300D03*
X-299259D03*
X-294141Y-32500D03*
X-299259D03*
X-298987Y-25950D03*
X-293869D03*
Y-20750D03*
X-298987D03*
X-299131Y-15250D03*
X-294013D03*
Y-9750D03*
X-299131D03*
X-298987Y-4450D03*
X-293869D03*
X-182209Y-52350D03*
X-177091D03*
X-178959Y-34470D03*
X-179059Y-10000D03*
X-178850Y-16500D03*
X-173841Y-34470D03*
X-173941Y-10000D03*
X-173750Y-16500D03*
G54D24*
G01X-874510Y-499000D02*
Y-493000D01*
X-871290Y-499000D01*
Y-493000D01*
G01X-867200Y-499000D02*
X-867760Y-498900D01*
X-868250Y-498500D01*
X-868670Y-497900D01*
X-868950Y-497200D01*
X-869090Y-496400D01*
Y-495600D01*
X-868950Y-494800D01*
X-868670Y-494100D01*
X-868250Y-493500D01*
X-867760Y-493100D01*
X-867200Y-493000D01*
X-866640Y-493100D01*
X-866150Y-493500D01*
X-865730Y-494100D01*
X-865450Y-494800D01*
X-865310Y-495600D01*
Y-496400D01*
X-865450Y-497200D01*
X-865730Y-497900D01*
X-866150Y-498500D01*
X-866640Y-498900D01*
X-867200Y-499000D01*
G01X-861500Y-493000D02*
Y-499000D01*
G01X-863110Y-493000D02*
X-859890D01*
G01X-856640D02*
X-854960D01*
G01X-855800D02*
Y-499000D01*
G01X-856640D02*
X-854960D01*
G01X-848560Y-493500D02*
X-848980Y-493200D01*
X-849470Y-493000D01*
X-850030D01*
X-850660Y-493300D01*
X-851150Y-493800D01*
X-851500Y-494400D01*
X-851780Y-495400D01*
X-851850Y-496300D01*
X-851710Y-497200D01*
X-851500Y-497800D01*
X-851080Y-498400D01*
X-850590Y-498800D01*
X-850100Y-499000D01*
X-849610D01*
X-849120Y-498800D01*
X-848700Y-498500D01*
X-848350Y-498100D01*
G01X-843000Y-499000D02*
X-845800D01*
Y-493000D01*
X-843000D01*
G01X-844120Y-495900D02*
X-845800D01*
G01X-833000Y-499000D02*
X-833560Y-498900D01*
X-834050Y-498500D01*
X-834470Y-497900D01*
X-834750Y-497200D01*
X-834890Y-496400D01*
Y-495600D01*
X-834750Y-494800D01*
X-834470Y-494100D01*
X-834050Y-493500D01*
X-833560Y-493100D01*
X-833000Y-493000D01*
X-832440Y-493100D01*
X-831950Y-493500D01*
X-831530Y-494100D01*
X-831250Y-494800D01*
X-831110Y-495600D01*
Y-496400D01*
X-831250Y-497200D01*
X-831530Y-497900D01*
X-831950Y-498500D01*
X-832440Y-498900D01*
X-833000Y-499000D01*
G01X-828630D02*
Y-493000D01*
X-825970D01*
G01X-826950Y-495900D02*
X-828630D01*
G01X-817300Y-499000D02*
Y-493000D01*
X-815620D01*
X-815060Y-493300D01*
X-814640Y-494000D01*
X-814500Y-494800D01*
X-814640Y-495600D01*
X-814990Y-496200D01*
X-815620Y-496500D01*
X-817300D01*
G01X-811600Y-499000D02*
Y-493000D01*
X-809850D01*
X-809290Y-493300D01*
X-808940Y-493700D01*
X-808800Y-494500D01*
X-808940Y-495300D01*
X-809360Y-495800D01*
X-809850Y-496100D01*
X-811600D01*
G01X-809850D02*
X-808800Y-499000D01*
G01X-804500D02*
X-805060Y-498900D01*
X-805550Y-498500D01*
X-805970Y-497900D01*
X-806250Y-497200D01*
X-806390Y-496400D01*
Y-495600D01*
X-806250Y-494800D01*
X-805970Y-494100D01*
X-805550Y-493500D01*
X-805060Y-493100D01*
X-804500Y-493000D01*
X-803940Y-493100D01*
X-803450Y-493500D01*
X-803030Y-494100D01*
X-802750Y-494800D01*
X-802610Y-495600D01*
Y-496400D01*
X-802750Y-497200D01*
X-803030Y-497900D01*
X-803450Y-498500D01*
X-803940Y-498900D01*
X-804500Y-499000D01*
G01X-800200D02*
Y-493000D01*
X-798520D01*
X-797960Y-493300D01*
X-797540Y-494000D01*
X-797400Y-494800D01*
X-797540Y-495600D01*
X-797890Y-496200D01*
X-798520Y-496500D01*
X-800200D01*
G01X-794500Y-499000D02*
Y-493000D01*
X-792750D01*
X-792190Y-493300D01*
X-791840Y-493700D01*
X-791700Y-494500D01*
X-791840Y-495300D01*
X-792260Y-495800D01*
X-792750Y-496100D01*
X-794500D01*
G01X-792750D02*
X-791700Y-499000D01*
G01X-788240Y-493000D02*
X-786560D01*
G01X-787400D02*
Y-499000D01*
G01X-788240D02*
X-786560D01*
G01X-780300D02*
X-783100D01*
Y-493000D01*
X-780300D01*
G01X-781420Y-495900D02*
X-783100D01*
G01X-776000Y-493000D02*
Y-499000D01*
G01X-777610Y-493000D02*
X-774390D01*
G01X-772050Y-499000D02*
X-770300Y-493000D01*
X-768550Y-499000D01*
G01X-769180Y-496900D02*
X-771420D01*
G01X-766000Y-499000D02*
Y-493000D01*
X-764250D01*
X-763690Y-493300D01*
X-763340Y-493700D01*
X-763200Y-494500D01*
X-763340Y-495300D01*
X-763760Y-495800D01*
X-764250Y-496100D01*
X-766000D01*
G01X-764250D02*
X-763200Y-499000D01*
G01X-758900D02*
Y-496300D01*
X-760300Y-493000D01*
G01X-757500D02*
X-758900Y-496300D01*
G01X-748900Y-499000D02*
Y-493000D01*
X-747220D01*
X-746660Y-493300D01*
X-746240Y-494000D01*
X-746100Y-494800D01*
X-746240Y-495600D01*
X-746590Y-496200D01*
X-747220Y-496500D01*
X-748900D01*
G01X-743200Y-499000D02*
Y-493000D01*
X-741450D01*
X-740890Y-493300D01*
X-740540Y-493700D01*
X-740400Y-494500D01*
X-740540Y-495300D01*
X-740960Y-495800D01*
X-741450Y-496100D01*
X-743200D01*
G01X-741450D02*
X-740400Y-499000D01*
G01X-736100D02*
X-736660Y-498900D01*
X-737150Y-498500D01*
X-737570Y-497900D01*
X-737850Y-497200D01*
X-737990Y-496400D01*
Y-495600D01*
X-737850Y-494800D01*
X-737570Y-494100D01*
X-737150Y-493500D01*
X-736660Y-493100D01*
X-736100Y-493000D01*
X-735540Y-493100D01*
X-735050Y-493500D01*
X-734630Y-494100D01*
X-734350Y-494800D01*
X-734210Y-495600D01*
Y-496400D01*
X-734350Y-497200D01*
X-734630Y-497900D01*
X-735050Y-498500D01*
X-735540Y-498900D01*
X-736100Y-499000D01*
G01X-731800D02*
Y-493000D01*
X-730120D01*
X-729560Y-493300D01*
X-729140Y-494000D01*
X-729000Y-494800D01*
X-729140Y-495600D01*
X-729490Y-496200D01*
X-730120Y-496500D01*
X-731800D01*
G01X-723300Y-499000D02*
X-726100D01*
Y-493000D01*
X-723300D01*
G01X-724420Y-495900D02*
X-726100D01*
G01X-720400Y-499000D02*
Y-493000D01*
X-718650D01*
X-718090Y-493300D01*
X-717740Y-493700D01*
X-717600Y-494500D01*
X-717740Y-495300D01*
X-718160Y-495800D01*
X-718650Y-496100D01*
X-720400D01*
G01X-718650D02*
X-717600Y-499000D01*
G01X-713300Y-493000D02*
Y-499000D01*
G01X-714910Y-493000D02*
X-711690D01*
G01X-707600Y-499000D02*
Y-496300D01*
X-709000Y-493000D01*
G01X-706200D02*
X-707600Y-496300D01*
G01X-701900Y-499200D02*
X-702040Y-499100D01*
Y-498900D01*
X-701900Y-498800D01*
X-701760Y-498900D01*
Y-499100D01*
X-701900Y-499200D01*
G01Y-496500D02*
X-702040Y-496400D01*
Y-496200D01*
X-701900Y-496100D01*
X-701760Y-496200D01*
Y-496400D01*
X-701900Y-496500D01*
G54D15*
X-1263189Y-172598D03*
X-1266339D03*
X-1269488D03*
X-1272638D03*
X-1274213Y-162756D03*
X-1271063D03*
X-1267913D03*
X-1264764D03*
X-1247441Y-172598D03*
X-1250591D03*
X-1253740D03*
X-1256890D03*
X-1260039D03*
X-1261614Y-162756D03*
X-1258465D03*
X-1255315D03*
X-1252165D03*
X-1249016D03*
X-1231693Y-172598D03*
X-1234843D03*
X-1237992D03*
X-1241142D03*
X-1244291D03*
X-1245866Y-162756D03*
X-1242717D03*
X-1239567D03*
X-1236417D03*
X-1233268D03*
X-1215945Y-172598D03*
X-1219094D03*
X-1222244D03*
X-1225394D03*
X-1228543D03*
X-1230118Y-162756D03*
X-1226968D03*
X-1223819D03*
X-1220669D03*
X-1217520D03*
X-396260Y-172598D03*
X-399409D03*
X-402559D03*
X-404134Y-162756D03*
X-400984D03*
X-397835D03*
X-380512Y-172598D03*
X-383661D03*
X-386811D03*
X-389961D03*
X-393110D03*
X-394685Y-162756D03*
X-391535D03*
X-388386D03*
X-385236D03*
X-382087D03*
X-364764Y-172598D03*
X-367913D03*
X-371063D03*
X-374213D03*
X-377362D03*
X-378937Y-162756D03*
X-375787D03*
X-372638D03*
X-369488D03*
X-366339D03*
X-349016Y-172598D03*
X-352165D03*
X-355315D03*
X-358465D03*
X-361614D03*
X-363189Y-162756D03*
X-360039D03*
X-356890D03*
X-353740D03*
X-350591D03*
X-345866Y-172598D03*
X-347441Y-162756D03*
G54D25*
G01X-1189333Y-572500D02*
Y-565500D01*
X-1187667D01*
X-1187000Y-565850D01*
X-1186500Y-566317D01*
X-1186083Y-567017D01*
X-1185750Y-567833D01*
X-1185667Y-569000D01*
X-1185750Y-570167D01*
X-1186083Y-570983D01*
X-1186500Y-571684D01*
X-1187000Y-572150D01*
X-1187667Y-572500D01*
X-1189333D01*
G01X-1180700D02*
X-1181367Y-572383D01*
X-1181950Y-571917D01*
X-1182450Y-571217D01*
X-1182783Y-570400D01*
X-1182950Y-569467D01*
Y-568533D01*
X-1182783Y-567600D01*
X-1182450Y-566783D01*
X-1181950Y-566083D01*
X-1181367Y-565617D01*
X-1180700Y-565500D01*
X-1180033Y-565617D01*
X-1179450Y-566083D01*
X-1178950Y-566783D01*
X-1178617Y-567600D01*
X-1178450Y-568533D01*
Y-569467D01*
X-1178617Y-570400D01*
X-1178950Y-571217D01*
X-1179450Y-571917D01*
X-1180033Y-572383D01*
X-1180700Y-572500D01*
G01X-1172067Y-566083D02*
X-1172567Y-565733D01*
X-1173150Y-565500D01*
X-1173817D01*
X-1174567Y-565850D01*
X-1175150Y-566433D01*
X-1175567Y-567133D01*
X-1175900Y-568300D01*
X-1175983Y-569350D01*
X-1175817Y-570400D01*
X-1175567Y-571100D01*
X-1175067Y-571800D01*
X-1174483Y-572267D01*
X-1173900Y-572500D01*
X-1173317D01*
X-1172733Y-572267D01*
X-1172233Y-571917D01*
X-1171817Y-571450D01*
G01X-1168933Y-565500D02*
Y-570517D01*
X-1168600Y-571567D01*
X-1167933Y-572267D01*
X-1167100Y-572500D01*
X-1166267Y-572267D01*
X-1165600Y-571567D01*
X-1165267Y-570517D01*
Y-565500D01*
G01X-1162467Y-572500D02*
Y-565500D01*
X-1160300Y-571333D01*
X-1158133Y-565500D01*
Y-572500D01*
G01X-1151833D02*
X-1155167D01*
Y-565500D01*
X-1151833D01*
G01X-1153167Y-568883D02*
X-1155167D01*
G01X-1148617Y-572500D02*
Y-565500D01*
X-1144783Y-572500D01*
Y-565500D01*
G01X-1139900D02*
Y-572500D01*
G01X-1141817Y-565500D02*
X-1137983D01*
G01X-1128217Y-572500D02*
Y-565500D01*
X-1124383Y-572500D01*
Y-565500D01*
G01X-1121333D02*
Y-570517D01*
X-1121000Y-571567D01*
X-1120333Y-572267D01*
X-1119500Y-572500D01*
X-1118667Y-572267D01*
X-1118000Y-571567D01*
X-1117667Y-570517D01*
Y-565500D01*
G01X-1114867Y-572500D02*
Y-565500D01*
X-1112700Y-571333D01*
X-1110533Y-565500D01*
Y-572500D01*
G01X-1105233Y-568767D02*
X-1104900Y-568417D01*
X-1104650Y-567833D01*
X-1104483Y-567017D01*
X-1104650Y-566317D01*
X-1104983Y-565850D01*
X-1105567Y-565500D01*
X-1107817D01*
Y-572500D01*
X-1105067D01*
X-1104483Y-572033D01*
X-1104150Y-571333D01*
X-1103983Y-570517D01*
X-1104150Y-569700D01*
X-1104650Y-569000D01*
X-1105233Y-568767D01*
X-1107817D01*
G01X-1097433Y-572500D02*
X-1100767D01*
Y-565500D01*
X-1097433D01*
G01X-1098767Y-568883D02*
X-1100767D01*
G01X-1093967Y-572500D02*
Y-565500D01*
X-1091883D01*
X-1091217Y-565850D01*
X-1090800Y-566317D01*
X-1090633Y-567250D01*
X-1090800Y-568183D01*
X-1091300Y-568767D01*
X-1091883Y-569117D01*
X-1093967D01*
G01X-1091883D02*
X-1090633Y-572500D01*
G01X-1189250Y-531567D02*
X-1188583Y-532150D01*
X-1187833Y-532500D01*
X-1187167D01*
X-1186500Y-532150D01*
X-1186000Y-531567D01*
X-1185750Y-530750D01*
X-1185917Y-529933D01*
X-1186333Y-529233D01*
X-1187083Y-528767D01*
X-1188083Y-528533D01*
X-1188667Y-528067D01*
X-1188917Y-527250D01*
X-1188750Y-526433D01*
X-1188333Y-525850D01*
X-1187750Y-525500D01*
X-1187167D01*
X-1186583Y-525733D01*
X-1186083Y-526317D01*
G01X-1182450Y-532500D02*
Y-525500D01*
G01X-1178950D02*
Y-532500D01*
G01Y-529000D02*
X-1182450D01*
G01X-1172233Y-532500D02*
X-1175567D01*
Y-525500D01*
X-1172233D01*
G01X-1173567Y-528883D02*
X-1175567D01*
G01X-1165433Y-532500D02*
X-1168767D01*
Y-525500D01*
X-1165433D01*
G01X-1166767Y-528883D02*
X-1168767D01*
G01X-1160300Y-525500D02*
Y-532500D01*
G01X-1162217Y-525500D02*
X-1158383D01*
G01X-1146700D02*
Y-532500D01*
G01X-1148617Y-525500D02*
X-1144783D01*
G01X-1140900D02*
X-1138900D01*
G01X-1139900D02*
Y-532500D01*
G01X-1140900D02*
X-1138900D01*
G01X-1133100Y-525500D02*
Y-532500D01*
G01X-1135017Y-525500D02*
X-1131183D01*
G01X-1127967D02*
Y-532500D01*
X-1124633D01*
G01X-1117833D02*
X-1121167D01*
Y-525500D01*
X-1117833D01*
G01X-1119167Y-528883D02*
X-1121167D01*
G01X-1112700Y-532733D02*
X-1112867Y-532617D01*
Y-532383D01*
X-1112700Y-532267D01*
X-1112533Y-532383D01*
Y-532617D01*
X-1112700Y-532733D01*
G01Y-529584D02*
X-1112867Y-529467D01*
Y-529233D01*
X-1112700Y-529117D01*
X-1112533Y-529233D01*
Y-529467D01*
X-1112700Y-529584D01*
G01X-1187500Y-485500D02*
Y-492500D01*
G01X-1189417Y-485500D02*
X-1185583D01*
G01X-1181700D02*
X-1179700D01*
G01X-1180700D02*
Y-492500D01*
G01X-1181700D02*
X-1179700D01*
G01X-1173900Y-485500D02*
Y-492500D01*
G01X-1175817Y-485500D02*
X-1171983D01*
G01X-1168767D02*
Y-492500D01*
X-1165433D01*
G01X-1158633D02*
X-1161967D01*
Y-485500D01*
X-1158633D01*
G01X-1159967Y-488883D02*
X-1161967D01*
G01X-916667Y-570000D02*
Y-563000D01*
X-914583D01*
X-913917Y-563350D01*
X-913500Y-563817D01*
X-913333Y-564750D01*
X-913500Y-565683D01*
X-914000Y-566267D01*
X-914583Y-566617D01*
X-916667D01*
G01X-914583D02*
X-913333Y-570000D01*
G01X-906533D02*
X-909867D01*
Y-563000D01*
X-906533D01*
G01X-907867Y-566383D02*
X-909867D01*
G01X-903483Y-563000D02*
X-901400Y-570000D01*
X-899317Y-563000D01*
G01X-907850Y-451567D02*
X-907183Y-452150D01*
X-906433Y-452500D01*
X-905767D01*
X-905100Y-452150D01*
X-904600Y-451567D01*
X-904350Y-450750D01*
X-904517Y-449933D01*
X-904933Y-449233D01*
X-905683Y-448767D01*
X-906683Y-448533D01*
X-907267Y-448067D01*
X-907517Y-447250D01*
X-907350Y-446433D01*
X-906933Y-445850D01*
X-906350Y-445500D01*
X-905767D01*
X-905183Y-445733D01*
X-904683Y-446317D01*
G01X-897467Y-446083D02*
X-897967Y-445733D01*
X-898550Y-445500D01*
X-899217D01*
X-899967Y-445850D01*
X-900550Y-446433D01*
X-900967Y-447133D01*
X-901300Y-448300D01*
X-901383Y-449350D01*
X-901217Y-450400D01*
X-900967Y-451100D01*
X-900467Y-451800D01*
X-899883Y-452267D01*
X-899300Y-452500D01*
X-898717D01*
X-898133Y-452267D01*
X-897633Y-451917D01*
X-897217Y-451450D01*
G01X-894583Y-452500D02*
X-892500Y-445500D01*
X-890417Y-452500D01*
G01X-891167Y-450050D02*
X-893833D01*
G01X-887367Y-445500D02*
Y-452500D01*
X-884033D01*
G01X-877233D02*
X-880567D01*
Y-445500D01*
X-877233D01*
G01X-878567Y-448883D02*
X-880567D01*
G01X-874333Y-572500D02*
Y-565500D01*
X-872667D01*
X-872000Y-565850D01*
X-871500Y-566317D01*
X-871083Y-567017D01*
X-870750Y-567833D01*
X-870667Y-569000D01*
X-870750Y-570167D01*
X-871083Y-570983D01*
X-871500Y-571684D01*
X-872000Y-572150D01*
X-872667Y-572500D01*
X-874333D01*
G01X-866700Y-565500D02*
X-864700D01*
G01X-865700D02*
Y-572500D01*
G01X-866700D02*
X-864700D01*
G01X-860650Y-571567D02*
X-859983Y-572150D01*
X-859233Y-572500D01*
X-858567D01*
X-857900Y-572150D01*
X-857400Y-571567D01*
X-857150Y-570750D01*
X-857317Y-569933D01*
X-857733Y-569233D01*
X-858483Y-568767D01*
X-859483Y-568533D01*
X-860067Y-568067D01*
X-860317Y-567250D01*
X-860150Y-566433D01*
X-859733Y-565850D01*
X-859150Y-565500D01*
X-858567D01*
X-857983Y-565733D01*
X-857483Y-566317D01*
G01X-850267Y-566083D02*
X-850767Y-565733D01*
X-851350Y-565500D01*
X-852017D01*
X-852767Y-565850D01*
X-853350Y-566433D01*
X-853767Y-567133D01*
X-854100Y-568300D01*
X-854183Y-569350D01*
X-854017Y-570400D01*
X-853767Y-571100D01*
X-853267Y-571800D01*
X-852683Y-572267D01*
X-852100Y-572500D01*
X-851517D01*
X-850933Y-572267D01*
X-850433Y-571917D01*
X-850017Y-571450D01*
G01X-846967Y-565500D02*
Y-572500D01*
X-843633D01*
G01X-838500D02*
X-839167Y-572383D01*
X-839750Y-571917D01*
X-840250Y-571217D01*
X-840583Y-570400D01*
X-840750Y-569467D01*
Y-568533D01*
X-840583Y-567600D01*
X-840250Y-566783D01*
X-839750Y-566083D01*
X-839167Y-565617D01*
X-838500Y-565500D01*
X-837833Y-565617D01*
X-837250Y-566083D01*
X-836750Y-566783D01*
X-836417Y-567600D01*
X-836250Y-568533D01*
Y-569467D01*
X-836417Y-570400D01*
X-836750Y-571217D01*
X-837250Y-571917D01*
X-837833Y-572383D01*
X-838500Y-572500D01*
G01X-833450Y-571567D02*
X-832783Y-572150D01*
X-832033Y-572500D01*
X-831367D01*
X-830700Y-572150D01*
X-830200Y-571567D01*
X-829950Y-570750D01*
X-830117Y-569933D01*
X-830533Y-569233D01*
X-831283Y-568767D01*
X-832283Y-568533D01*
X-832867Y-568067D01*
X-833117Y-567250D01*
X-832950Y-566433D01*
X-832533Y-565850D01*
X-831950Y-565500D01*
X-831367D01*
X-830783Y-565733D01*
X-830283Y-566317D01*
G01X-823233Y-572500D02*
X-826567D01*
Y-565500D01*
X-823233D01*
G01X-824567Y-568883D02*
X-826567D01*
G01X-819933Y-572500D02*
Y-565500D01*
X-818267D01*
X-817600Y-565850D01*
X-817100Y-566317D01*
X-816683Y-567017D01*
X-816350Y-567833D01*
X-816267Y-569000D01*
X-816350Y-570167D01*
X-816683Y-570983D01*
X-817100Y-571684D01*
X-817600Y-572150D01*
X-818267Y-572500D01*
X-819933D01*
G01X-807000Y-565500D02*
X-805833Y-572500D01*
X-804500Y-565500D01*
X-803167Y-572500D01*
X-802000Y-565500D01*
G01X-798700D02*
X-796700D01*
G01X-797700D02*
Y-572500D01*
G01X-798700D02*
X-796700D01*
G01X-790900Y-565500D02*
Y-572500D01*
G01X-792817Y-565500D02*
X-788983D01*
G01X-785850Y-572500D02*
Y-565500D01*
G01X-782350D02*
Y-572500D01*
G01Y-569000D02*
X-785850D01*
G01X-777300Y-572500D02*
X-777967Y-572383D01*
X-778550Y-571917D01*
X-779050Y-571217D01*
X-779383Y-570400D01*
X-779550Y-569467D01*
Y-568533D01*
X-779383Y-567600D01*
X-779050Y-566783D01*
X-778550Y-566083D01*
X-777967Y-565617D01*
X-777300Y-565500D01*
X-776633Y-565617D01*
X-776050Y-566083D01*
X-775550Y-566783D01*
X-775217Y-567600D01*
X-775050Y-568533D01*
Y-569467D01*
X-775217Y-570400D01*
X-775550Y-571217D01*
X-776050Y-571917D01*
X-776633Y-572383D01*
X-777300Y-572500D01*
G01X-772333Y-565500D02*
Y-570517D01*
X-772000Y-571567D01*
X-771333Y-572267D01*
X-770500Y-572500D01*
X-769667Y-572267D01*
X-769000Y-571567D01*
X-768667Y-570517D01*
Y-565500D01*
G01X-763700D02*
Y-572500D01*
G01X-765617Y-565500D02*
X-761783D01*
G01X-750100D02*
Y-572500D01*
G01X-752017Y-565500D02*
X-748183D01*
G01X-745050Y-572500D02*
Y-565500D01*
G01X-741550D02*
Y-572500D01*
G01Y-569000D02*
X-745050D01*
G01X-734833Y-572500D02*
X-738167D01*
Y-565500D01*
X-734833D01*
G01X-736167Y-568883D02*
X-738167D01*
G01X-724567Y-572500D02*
Y-565500D01*
X-722567D01*
X-721900Y-565850D01*
X-721400Y-566667D01*
X-721233Y-567600D01*
X-721400Y-568533D01*
X-721817Y-569233D01*
X-722567Y-569584D01*
X-724567D01*
G01X-717767Y-572500D02*
Y-565500D01*
X-715683D01*
X-715017Y-565850D01*
X-714600Y-566317D01*
X-714433Y-567250D01*
X-714600Y-568183D01*
X-715100Y-568767D01*
X-715683Y-569117D01*
X-717767D01*
G01X-715683D02*
X-714433Y-572500D01*
G01X-710300Y-565500D02*
X-708300D01*
G01X-709300D02*
Y-572500D01*
G01X-710300D02*
X-708300D01*
G01X-702500D02*
X-703167Y-572383D01*
X-703750Y-571917D01*
X-704250Y-571217D01*
X-704583Y-570400D01*
X-704750Y-569467D01*
Y-568533D01*
X-704583Y-567600D01*
X-704250Y-566783D01*
X-703750Y-566083D01*
X-703167Y-565617D01*
X-702500Y-565500D01*
X-701833Y-565617D01*
X-701250Y-566083D01*
X-700750Y-566783D01*
X-700417Y-567600D01*
X-700250Y-568533D01*
Y-569467D01*
X-700417Y-570400D01*
X-700750Y-571217D01*
X-701250Y-571917D01*
X-701833Y-572383D01*
X-702500Y-572500D01*
G01X-697367D02*
Y-565500D01*
X-695283D01*
X-694617Y-565850D01*
X-694200Y-566317D01*
X-694033Y-567250D01*
X-694200Y-568183D01*
X-694700Y-568767D01*
X-695283Y-569117D01*
X-697367D01*
G01X-695283D02*
X-694033Y-572500D01*
G01X-684600Y-565500D02*
X-683433Y-572500D01*
X-682100Y-565500D01*
X-680767Y-572500D01*
X-679600Y-565500D01*
G01X-676967Y-572500D02*
Y-565500D01*
X-674883D01*
X-674217Y-565850D01*
X-673800Y-566317D01*
X-673633Y-567250D01*
X-673800Y-568183D01*
X-674300Y-568767D01*
X-674883Y-569117D01*
X-676967D01*
G01X-674883D02*
X-673633Y-572500D01*
G01X-669500Y-565500D02*
X-667500D01*
G01X-668500D02*
Y-572500D01*
G01X-669500D02*
X-667500D01*
G01X-661700Y-565500D02*
Y-572500D01*
G01X-663617Y-565500D02*
X-659783D01*
G01X-654900D02*
Y-572500D01*
G01X-656817Y-565500D02*
X-652983D01*
G01X-646433Y-572500D02*
X-649767D01*
Y-565500D01*
X-646433D01*
G01X-647767Y-568883D02*
X-649767D01*
G01X-643217Y-572500D02*
Y-565500D01*
X-639383Y-572500D01*
Y-565500D01*
G01X-625867Y-566083D02*
X-626367Y-565733D01*
X-626950Y-565500D01*
X-627617D01*
X-628367Y-565850D01*
X-628950Y-566433D01*
X-629367Y-567133D01*
X-629700Y-568300D01*
X-629783Y-569350D01*
X-629617Y-570400D01*
X-629367Y-571100D01*
X-628867Y-571800D01*
X-628283Y-572267D01*
X-627700Y-572500D01*
X-627117D01*
X-626533Y-572267D01*
X-626033Y-571917D01*
X-625617Y-571450D01*
G01X-620900Y-572500D02*
X-621567Y-572383D01*
X-622150Y-571917D01*
X-622650Y-571217D01*
X-622983Y-570400D01*
X-623150Y-569467D01*
Y-568533D01*
X-622983Y-567600D01*
X-622650Y-566783D01*
X-622150Y-566083D01*
X-621567Y-565617D01*
X-620900Y-565500D01*
X-620233Y-565617D01*
X-619650Y-566083D01*
X-619150Y-566783D01*
X-618817Y-567600D01*
X-618650Y-568533D01*
Y-569467D01*
X-618817Y-570400D01*
X-619150Y-571217D01*
X-619650Y-571917D01*
X-620233Y-572383D01*
X-620900Y-572500D01*
G01X-616017D02*
Y-565500D01*
X-612183Y-572500D01*
Y-565500D01*
G01X-609050Y-571567D02*
X-608383Y-572150D01*
X-607633Y-572500D01*
X-606967D01*
X-606300Y-572150D01*
X-605800Y-571567D01*
X-605550Y-570750D01*
X-605717Y-569933D01*
X-606133Y-569233D01*
X-606883Y-568767D01*
X-607883Y-568533D01*
X-608467Y-568067D01*
X-608717Y-567250D01*
X-608550Y-566433D01*
X-608133Y-565850D01*
X-607550Y-565500D01*
X-606967D01*
X-606383Y-565733D01*
X-605883Y-566317D01*
G01X-598833Y-572500D02*
X-602167D01*
Y-565500D01*
X-598833D01*
G01X-600167Y-568883D02*
X-602167D01*
G01X-595617Y-572500D02*
Y-565500D01*
X-591783Y-572500D01*
Y-565500D01*
G01X-586900D02*
Y-572500D01*
G01X-588817Y-565500D02*
X-584983D01*
G01X-872500Y-587500D02*
X-873167Y-587383D01*
X-873750Y-586917D01*
X-874250Y-586217D01*
X-874583Y-585400D01*
X-874750Y-584467D01*
Y-583533D01*
X-874583Y-582600D01*
X-874250Y-581783D01*
X-873750Y-581083D01*
X-873167Y-580617D01*
X-872500Y-580500D01*
X-871833Y-580617D01*
X-871250Y-581083D01*
X-870750Y-581783D01*
X-870417Y-582600D01*
X-870250Y-583533D01*
Y-584467D01*
X-870417Y-585400D01*
X-870750Y-586217D01*
X-871250Y-586917D01*
X-871833Y-587383D01*
X-872500Y-587500D01*
G01X-867283D02*
Y-580500D01*
X-864117D01*
G01X-865283Y-583883D02*
X-867283D01*
G01X-854267Y-587500D02*
Y-580500D01*
X-852100Y-586333D01*
X-849933Y-580500D01*
Y-587500D01*
G01X-846300Y-580500D02*
X-844300D01*
G01X-845300D02*
Y-587500D01*
G01X-846300D02*
X-844300D01*
G01X-836667Y-581083D02*
X-837167Y-580733D01*
X-837750Y-580500D01*
X-838417D01*
X-839167Y-580850D01*
X-839750Y-581433D01*
X-840167Y-582133D01*
X-840500Y-583300D01*
X-840583Y-584350D01*
X-840417Y-585400D01*
X-840167Y-586100D01*
X-839667Y-586800D01*
X-839083Y-587267D01*
X-838500Y-587500D01*
X-837917D01*
X-837333Y-587267D01*
X-836833Y-586917D01*
X-836417Y-586450D01*
G01X-833367Y-587500D02*
Y-580500D01*
X-831283D01*
X-830617Y-580850D01*
X-830200Y-581317D01*
X-830033Y-582250D01*
X-830200Y-583183D01*
X-830700Y-583767D01*
X-831283Y-584117D01*
X-833367D01*
G01X-831283D02*
X-830033Y-587500D01*
G01X-824900D02*
X-825567Y-587383D01*
X-826150Y-586917D01*
X-826650Y-586217D01*
X-826983Y-585400D01*
X-827150Y-584467D01*
Y-583533D01*
X-826983Y-582600D01*
X-826650Y-581783D01*
X-826150Y-581083D01*
X-825567Y-580617D01*
X-824900Y-580500D01*
X-824233Y-580617D01*
X-823650Y-581083D01*
X-823150Y-581783D01*
X-822817Y-582600D01*
X-822650Y-583533D01*
Y-584467D01*
X-822817Y-585400D01*
X-823150Y-586217D01*
X-823650Y-586917D01*
X-824233Y-587383D01*
X-824900Y-587500D01*
G01X-819850Y-586567D02*
X-819183Y-587150D01*
X-818433Y-587500D01*
X-817767D01*
X-817100Y-587150D01*
X-816600Y-586567D01*
X-816350Y-585750D01*
X-816517Y-584933D01*
X-816933Y-584233D01*
X-817683Y-583767D01*
X-818683Y-583533D01*
X-819267Y-583067D01*
X-819517Y-582250D01*
X-819350Y-581433D01*
X-818933Y-580850D01*
X-818350Y-580500D01*
X-817767D01*
X-817183Y-580733D01*
X-816683Y-581317D01*
G01X-811300Y-587500D02*
X-811967Y-587383D01*
X-812550Y-586917D01*
X-813050Y-586217D01*
X-813383Y-585400D01*
X-813550Y-584467D01*
Y-583533D01*
X-813383Y-582600D01*
X-813050Y-581783D01*
X-812550Y-581083D01*
X-811967Y-580617D01*
X-811300Y-580500D01*
X-810633Y-580617D01*
X-810050Y-581083D01*
X-809550Y-581783D01*
X-809217Y-582600D01*
X-809050Y-583533D01*
Y-584467D01*
X-809217Y-585400D01*
X-809550Y-586217D01*
X-810050Y-586917D01*
X-810633Y-587383D01*
X-811300Y-587500D01*
G01X-806083D02*
Y-580500D01*
X-802917D01*
G01X-804083Y-583883D02*
X-806083D01*
G01X-797700Y-580500D02*
Y-587500D01*
G01X-799617Y-580500D02*
X-795783D01*
G01X-782267Y-581083D02*
X-782767Y-580733D01*
X-783350Y-580500D01*
X-784017D01*
X-784767Y-580850D01*
X-785350Y-581433D01*
X-785767Y-582133D01*
X-786100Y-583300D01*
X-786183Y-584350D01*
X-786017Y-585400D01*
X-785767Y-586100D01*
X-785267Y-586800D01*
X-784683Y-587267D01*
X-784100Y-587500D01*
X-783517D01*
X-782933Y-587267D01*
X-782433Y-586917D01*
X-782017Y-586450D01*
G01X-777300Y-587500D02*
X-777967Y-587383D01*
X-778550Y-586917D01*
X-779050Y-586217D01*
X-779383Y-585400D01*
X-779550Y-584467D01*
Y-583533D01*
X-779383Y-582600D01*
X-779050Y-581783D01*
X-778550Y-581083D01*
X-777967Y-580617D01*
X-777300Y-580500D01*
X-776633Y-580617D01*
X-776050Y-581083D01*
X-775550Y-581783D01*
X-775217Y-582600D01*
X-775050Y-583533D01*
Y-584467D01*
X-775217Y-585400D01*
X-775550Y-586217D01*
X-776050Y-586917D01*
X-776633Y-587383D01*
X-777300Y-587500D01*
G01X-772167D02*
Y-580500D01*
X-770083D01*
X-769417Y-580850D01*
X-769000Y-581317D01*
X-768833Y-582250D01*
X-769000Y-583183D01*
X-769500Y-583767D01*
X-770083Y-584117D01*
X-772167D01*
G01X-770083D02*
X-768833Y-587500D01*
G01X-765367D02*
Y-580500D01*
X-763367D01*
X-762700Y-580850D01*
X-762200Y-581667D01*
X-762033Y-582600D01*
X-762200Y-583533D01*
X-762617Y-584233D01*
X-763367Y-584584D01*
X-765367D01*
G01X-756900Y-587500D02*
X-757567Y-587383D01*
X-758150Y-586917D01*
X-758650Y-586217D01*
X-758983Y-585400D01*
X-759150Y-584467D01*
Y-583533D01*
X-758983Y-582600D01*
X-758650Y-581783D01*
X-758150Y-581083D01*
X-757567Y-580617D01*
X-756900Y-580500D01*
X-756233Y-580617D01*
X-755650Y-581083D01*
X-755150Y-581783D01*
X-754817Y-582600D01*
X-754650Y-583533D01*
Y-584467D01*
X-754817Y-585400D01*
X-755150Y-586217D01*
X-755650Y-586917D01*
X-756233Y-587383D01*
X-756900Y-587500D01*
G01X-751767D02*
Y-580500D01*
X-749683D01*
X-749017Y-580850D01*
X-748600Y-581317D01*
X-748433Y-582250D01*
X-748600Y-583183D01*
X-749100Y-583767D01*
X-749683Y-584117D01*
X-751767D01*
G01X-749683D02*
X-748433Y-587500D01*
G01X-745383D02*
X-743300Y-580500D01*
X-741217Y-587500D01*
G01X-741967Y-585050D02*
X-744633D01*
G01X-736500Y-580500D02*
Y-587500D01*
G01X-738417Y-580500D02*
X-734583D01*
G01X-730700D02*
X-728700D01*
G01X-729700D02*
Y-587500D01*
G01X-730700D02*
X-728700D01*
G01X-722900D02*
X-723567Y-587383D01*
X-724150Y-586917D01*
X-724650Y-586217D01*
X-724983Y-585400D01*
X-725150Y-584467D01*
Y-583533D01*
X-724983Y-582600D01*
X-724650Y-581783D01*
X-724150Y-581083D01*
X-723567Y-580617D01*
X-722900Y-580500D01*
X-722233Y-580617D01*
X-721650Y-581083D01*
X-721150Y-581783D01*
X-720817Y-582600D01*
X-720650Y-583533D01*
Y-584467D01*
X-720817Y-585400D01*
X-721150Y-586217D01*
X-721650Y-586917D01*
X-722233Y-587383D01*
X-722900Y-587500D01*
G01X-718017D02*
Y-580500D01*
X-714183Y-587500D01*
Y-580500D01*
G01X-709300Y-587733D02*
X-709467Y-587617D01*
Y-587383D01*
X-709300Y-587267D01*
X-709133Y-587383D01*
Y-587617D01*
X-709300Y-587733D01*
G01X-870667Y-551083D02*
X-871167Y-550733D01*
X-871750Y-550500D01*
X-872417D01*
X-873167Y-550850D01*
X-873750Y-551433D01*
X-874167Y-552133D01*
X-874500Y-553300D01*
X-874583Y-554350D01*
X-874417Y-555400D01*
X-874167Y-556100D01*
X-873667Y-556800D01*
X-873083Y-557267D01*
X-872500Y-557500D01*
X-871917D01*
X-871333Y-557267D01*
X-870833Y-556917D01*
X-870417Y-556450D01*
G01X-865700Y-557500D02*
X-866367Y-557383D01*
X-866950Y-556917D01*
X-867450Y-556217D01*
X-867783Y-555400D01*
X-867950Y-554467D01*
Y-553533D01*
X-867783Y-552600D01*
X-867450Y-551783D01*
X-866950Y-551083D01*
X-866367Y-550617D01*
X-865700Y-550500D01*
X-865033Y-550617D01*
X-864450Y-551083D01*
X-863950Y-551783D01*
X-863617Y-552600D01*
X-863450Y-553533D01*
Y-554467D01*
X-863617Y-555400D01*
X-863950Y-556217D01*
X-864450Y-556917D01*
X-865033Y-557383D01*
X-865700Y-557500D01*
G01X-860817D02*
Y-550500D01*
X-856983Y-557500D01*
Y-550500D01*
G01X-853683Y-557500D02*
Y-550500D01*
X-850517D01*
G01X-851683Y-553883D02*
X-853683D01*
G01X-846300Y-550500D02*
X-844300D01*
G01X-845300D02*
Y-557500D01*
G01X-846300D02*
X-844300D01*
G01X-840333D02*
Y-550500D01*
X-838667D01*
X-838000Y-550850D01*
X-837500Y-551317D01*
X-837083Y-552017D01*
X-836750Y-552833D01*
X-836667Y-554000D01*
X-836750Y-555167D01*
X-837083Y-555983D01*
X-837500Y-556684D01*
X-838000Y-557150D01*
X-838667Y-557500D01*
X-840333D01*
G01X-830033D02*
X-833367D01*
Y-550500D01*
X-830033D01*
G01X-831367Y-553883D02*
X-833367D01*
G01X-826817Y-557500D02*
Y-550500D01*
X-822983Y-557500D01*
Y-550500D01*
G01X-816267Y-551083D02*
X-816767Y-550733D01*
X-817350Y-550500D01*
X-818017D01*
X-818767Y-550850D01*
X-819350Y-551433D01*
X-819767Y-552133D01*
X-820100Y-553300D01*
X-820183Y-554350D01*
X-820017Y-555400D01*
X-819767Y-556100D01*
X-819267Y-556800D01*
X-818683Y-557267D01*
X-818100Y-557500D01*
X-817517D01*
X-816933Y-557267D01*
X-816433Y-556917D01*
X-816017Y-556450D01*
G01X-809633Y-557500D02*
X-812967D01*
Y-550500D01*
X-809633D01*
G01X-810967Y-553883D02*
X-812967D01*
G01X-799783Y-557500D02*
X-797700Y-550500D01*
X-795617Y-557500D01*
G01X-796367Y-555050D02*
X-799033D01*
G01X-792817Y-557500D02*
Y-550500D01*
X-788983Y-557500D01*
Y-550500D01*
G01X-785933Y-557500D02*
Y-550500D01*
X-784267D01*
X-783600Y-550850D01*
X-783100Y-551317D01*
X-782683Y-552017D01*
X-782350Y-552833D01*
X-782267Y-554000D01*
X-782350Y-555167D01*
X-782683Y-555983D01*
X-783100Y-556684D01*
X-783600Y-557150D01*
X-784267Y-557500D01*
X-785933D01*
G01X-771500Y-550500D02*
X-769500D01*
G01X-770500D02*
Y-557500D01*
G01X-771500D02*
X-769500D01*
G01X-763700Y-550500D02*
Y-557500D01*
G01X-765617Y-550500D02*
X-761783D01*
G01X-758650Y-556567D02*
X-757983Y-557150D01*
X-757233Y-557500D01*
X-756567D01*
X-755900Y-557150D01*
X-755400Y-556567D01*
X-755150Y-555750D01*
X-755317Y-554933D01*
X-755733Y-554233D01*
X-756483Y-553767D01*
X-757483Y-553533D01*
X-758067Y-553067D01*
X-758317Y-552250D01*
X-758150Y-551433D01*
X-757733Y-550850D01*
X-757150Y-550500D01*
X-756567D01*
X-755983Y-550733D01*
X-755483Y-551317D01*
G01X-741467Y-551083D02*
X-741967Y-550733D01*
X-742550Y-550500D01*
X-743217D01*
X-743967Y-550850D01*
X-744550Y-551433D01*
X-744967Y-552133D01*
X-745300Y-553300D01*
X-745383Y-554350D01*
X-745217Y-555400D01*
X-744967Y-556100D01*
X-744467Y-556800D01*
X-743883Y-557267D01*
X-743300Y-557500D01*
X-742717D01*
X-742133Y-557267D01*
X-741633Y-556917D01*
X-741217Y-556450D01*
G01X-736500Y-557500D02*
X-737167Y-557383D01*
X-737750Y-556917D01*
X-738250Y-556217D01*
X-738583Y-555400D01*
X-738750Y-554467D01*
Y-553533D01*
X-738583Y-552600D01*
X-738250Y-551783D01*
X-737750Y-551083D01*
X-737167Y-550617D01*
X-736500Y-550500D01*
X-735833Y-550617D01*
X-735250Y-551083D01*
X-734750Y-551783D01*
X-734417Y-552600D01*
X-734250Y-553533D01*
Y-554467D01*
X-734417Y-555400D01*
X-734750Y-556217D01*
X-735250Y-556917D01*
X-735833Y-557383D01*
X-736500Y-557500D01*
G01X-731617D02*
Y-550500D01*
X-727783Y-557500D01*
Y-550500D01*
G01X-722900D02*
Y-557500D01*
G01X-724817Y-550500D02*
X-720983D01*
G01X-714433Y-557500D02*
X-717767D01*
Y-550500D01*
X-714433D01*
G01X-715767Y-553883D02*
X-717767D01*
G01X-711217Y-557500D02*
Y-550500D01*
X-707383Y-557500D01*
Y-550500D01*
G01X-702500D02*
Y-557500D01*
G01X-704417Y-550500D02*
X-700583D01*
G01X-697450Y-556567D02*
X-696783Y-557150D01*
X-696033Y-557500D01*
X-695367D01*
X-694700Y-557150D01*
X-694200Y-556567D01*
X-693950Y-555750D01*
X-694117Y-554933D01*
X-694533Y-554233D01*
X-695283Y-553767D01*
X-696283Y-553533D01*
X-696867Y-553067D01*
X-697117Y-552250D01*
X-696950Y-551433D01*
X-696533Y-550850D01*
X-695950Y-550500D01*
X-695367D01*
X-694783Y-550733D01*
X-694283Y-551317D01*
G01X-684267Y-557500D02*
Y-550500D01*
X-682100Y-556333D01*
X-679933Y-550500D01*
Y-557500D01*
G01X-677383D02*
X-675300Y-550500D01*
X-673217Y-557500D01*
G01X-673967Y-555050D02*
X-676633D01*
G01X-668500Y-557500D02*
Y-554350D01*
X-670167Y-550500D01*
G01X-666833D02*
X-668500Y-554350D01*
G01X-656817Y-557500D02*
Y-550500D01*
X-652983Y-557500D01*
Y-550500D01*
G01X-648100Y-557500D02*
X-648767Y-557383D01*
X-649350Y-556917D01*
X-649850Y-556217D01*
X-650183Y-555400D01*
X-650350Y-554467D01*
Y-553533D01*
X-650183Y-552600D01*
X-649850Y-551783D01*
X-649350Y-551083D01*
X-648767Y-550617D01*
X-648100Y-550500D01*
X-647433Y-550617D01*
X-646850Y-551083D01*
X-646350Y-551783D01*
X-646017Y-552600D01*
X-645850Y-553533D01*
Y-554467D01*
X-646017Y-555400D01*
X-646350Y-556217D01*
X-646850Y-556917D01*
X-647433Y-557383D01*
X-648100Y-557500D01*
G01X-641300Y-550500D02*
Y-557500D01*
G01X-643217Y-550500D02*
X-639383D01*
G01X-627033Y-553767D02*
X-626700Y-553417D01*
X-626450Y-552833D01*
X-626283Y-552017D01*
X-626450Y-551317D01*
X-626783Y-550850D01*
X-627367Y-550500D01*
X-629617D01*
Y-557500D01*
X-626867D01*
X-626283Y-557033D01*
X-625950Y-556333D01*
X-625783Y-555517D01*
X-625950Y-554700D01*
X-626450Y-554000D01*
X-627033Y-553767D01*
X-629617D01*
G01X-619233Y-557500D02*
X-622567D01*
Y-550500D01*
X-619233D01*
G01X-620567Y-553883D02*
X-622567D01*
G01X-870667Y-536083D02*
X-871167Y-535733D01*
X-871750Y-535500D01*
X-872417D01*
X-873167Y-535850D01*
X-873750Y-536433D01*
X-874167Y-537133D01*
X-874500Y-538300D01*
X-874583Y-539350D01*
X-874417Y-540400D01*
X-874167Y-541100D01*
X-873667Y-541800D01*
X-873083Y-542267D01*
X-872500Y-542500D01*
X-871917D01*
X-871333Y-542267D01*
X-870833Y-541917D01*
X-870417Y-541450D01*
G01X-865700Y-542500D02*
X-866367Y-542383D01*
X-866950Y-541917D01*
X-867450Y-541217D01*
X-867783Y-540400D01*
X-867950Y-539467D01*
Y-538533D01*
X-867783Y-537600D01*
X-867450Y-536783D01*
X-866950Y-536083D01*
X-866367Y-535617D01*
X-865700Y-535500D01*
X-865033Y-535617D01*
X-864450Y-536083D01*
X-863950Y-536783D01*
X-863617Y-537600D01*
X-863450Y-538533D01*
Y-539467D01*
X-863617Y-540400D01*
X-863950Y-541217D01*
X-864450Y-541917D01*
X-865033Y-542383D01*
X-865700Y-542500D01*
G01X-860567D02*
Y-535500D01*
X-858483D01*
X-857817Y-535850D01*
X-857400Y-536317D01*
X-857233Y-537250D01*
X-857400Y-538183D01*
X-857900Y-538767D01*
X-858483Y-539117D01*
X-860567D01*
G01X-858483D02*
X-857233Y-542500D01*
G01X-853767D02*
Y-535500D01*
X-851767D01*
X-851100Y-535850D01*
X-850600Y-536667D01*
X-850433Y-537600D01*
X-850600Y-538533D01*
X-851017Y-539233D01*
X-851767Y-539584D01*
X-853767D01*
G01X-845300Y-542500D02*
X-845967Y-542383D01*
X-846550Y-541917D01*
X-847050Y-541217D01*
X-847383Y-540400D01*
X-847550Y-539467D01*
Y-538533D01*
X-847383Y-537600D01*
X-847050Y-536783D01*
X-846550Y-536083D01*
X-845967Y-535617D01*
X-845300Y-535500D01*
X-844633Y-535617D01*
X-844050Y-536083D01*
X-843550Y-536783D01*
X-843217Y-537600D01*
X-843050Y-538533D01*
Y-539467D01*
X-843217Y-540400D01*
X-843550Y-541217D01*
X-844050Y-541917D01*
X-844633Y-542383D01*
X-845300Y-542500D01*
G01X-840167D02*
Y-535500D01*
X-838083D01*
X-837417Y-535850D01*
X-837000Y-536317D01*
X-836833Y-537250D01*
X-837000Y-538183D01*
X-837500Y-538767D01*
X-838083Y-539117D01*
X-840167D01*
G01X-838083D02*
X-836833Y-542500D01*
G01X-833783D02*
X-831700Y-535500D01*
X-829617Y-542500D01*
G01X-830367Y-540050D02*
X-833033D01*
G01X-824900Y-535500D02*
Y-542500D01*
G01X-826817Y-535500D02*
X-822983D01*
G01X-819100D02*
X-817100D01*
G01X-818100D02*
Y-542500D01*
G01X-819100D02*
X-817100D01*
G01X-811300D02*
X-811967Y-542383D01*
X-812550Y-541917D01*
X-813050Y-541217D01*
X-813383Y-540400D01*
X-813550Y-539467D01*
Y-538533D01*
X-813383Y-537600D01*
X-813050Y-536783D01*
X-812550Y-536083D01*
X-811967Y-535617D01*
X-811300Y-535500D01*
X-810633Y-535617D01*
X-810050Y-536083D01*
X-809550Y-536783D01*
X-809217Y-537600D01*
X-809050Y-538533D01*
Y-539467D01*
X-809217Y-540400D01*
X-809550Y-541217D01*
X-810050Y-541917D01*
X-810633Y-542383D01*
X-811300Y-542500D01*
G01X-806417D02*
Y-535500D01*
X-802583Y-542500D01*
Y-535500D01*
G01X-797700Y-542733D02*
X-797867Y-542617D01*
Y-542383D01*
X-797700Y-542267D01*
X-797533Y-542383D01*
Y-542617D01*
X-797700Y-542733D01*
G01X-784100Y-535500D02*
Y-542500D01*
G01X-786017Y-535500D02*
X-782183D01*
G01X-779050Y-542500D02*
Y-535500D01*
G01X-775550D02*
Y-542500D01*
G01Y-539000D02*
X-779050D01*
G01X-771500Y-535500D02*
X-769500D01*
G01X-770500D02*
Y-542500D01*
G01X-771500D02*
X-769500D01*
G01X-765450Y-541567D02*
X-764783Y-542150D01*
X-764033Y-542500D01*
X-763367D01*
X-762700Y-542150D01*
X-762200Y-541567D01*
X-761950Y-540750D01*
X-762117Y-539933D01*
X-762533Y-539233D01*
X-763283Y-538767D01*
X-764283Y-538533D01*
X-764867Y-538067D01*
X-765117Y-537250D01*
X-764950Y-536433D01*
X-764533Y-535850D01*
X-763950Y-535500D01*
X-763367D01*
X-762783Y-535733D01*
X-762283Y-536317D01*
G01X-751933Y-542500D02*
Y-535500D01*
X-750267D01*
X-749600Y-535850D01*
X-749100Y-536317D01*
X-748683Y-537017D01*
X-748350Y-537833D01*
X-748267Y-539000D01*
X-748350Y-540167D01*
X-748683Y-540983D01*
X-749100Y-541684D01*
X-749600Y-542150D01*
X-750267Y-542500D01*
X-751933D01*
G01X-744967D02*
Y-535500D01*
X-742883D01*
X-742217Y-535850D01*
X-741800Y-536317D01*
X-741633Y-537250D01*
X-741800Y-538183D01*
X-742300Y-538767D01*
X-742883Y-539117D01*
X-744967D01*
G01X-742883D02*
X-741633Y-542500D01*
G01X-738583D02*
X-736500Y-535500D01*
X-734417Y-542500D01*
G01X-735167Y-540050D02*
X-737833D01*
G01X-732200Y-535500D02*
X-731033Y-542500D01*
X-729700Y-535500D01*
X-728367Y-542500D01*
X-727200Y-535500D01*
G01X-723900D02*
X-721900D01*
G01X-722900D02*
Y-542500D01*
G01X-723900D02*
X-721900D01*
G01X-718017D02*
Y-535500D01*
X-714183Y-542500D01*
Y-535500D01*
G01X-708800Y-539000D02*
X-707133D01*
Y-541100D01*
X-707633Y-541800D01*
X-708217Y-542267D01*
X-709050Y-542500D01*
X-709883Y-542267D01*
X-710467Y-541800D01*
X-710967Y-541100D01*
X-711300Y-540283D01*
X-711467Y-539350D01*
Y-538533D01*
X-711300Y-537833D01*
X-710967Y-537017D01*
X-710467Y-536317D01*
X-709967Y-535850D01*
X-709300Y-535500D01*
X-708717D01*
X-708050Y-535733D01*
X-707550Y-536200D01*
G01X-696700Y-535500D02*
X-694700D01*
G01X-695700D02*
Y-542500D01*
G01X-696700D02*
X-694700D01*
G01X-690650Y-541567D02*
X-689983Y-542150D01*
X-689233Y-542500D01*
X-688567D01*
X-687900Y-542150D01*
X-687400Y-541567D01*
X-687150Y-540750D01*
X-687317Y-539933D01*
X-687733Y-539233D01*
X-688483Y-538767D01*
X-689483Y-538533D01*
X-690067Y-538067D01*
X-690317Y-537250D01*
X-690150Y-536433D01*
X-689733Y-535850D01*
X-689150Y-535500D01*
X-688567D01*
X-687983Y-535733D01*
X-687483Y-536317D01*
G01X-676967Y-542500D02*
Y-535500D01*
X-674883D01*
X-674217Y-535850D01*
X-673800Y-536317D01*
X-673633Y-537250D01*
X-673800Y-538183D01*
X-674300Y-538767D01*
X-674883Y-539117D01*
X-676967D01*
G01X-674883D02*
X-673633Y-542500D01*
G01X-666833D02*
X-670167D01*
Y-535500D01*
X-666833D01*
G01X-668167Y-538883D02*
X-670167D01*
G01X-659867Y-536083D02*
X-660367Y-535733D01*
X-660950Y-535500D01*
X-661617D01*
X-662367Y-535850D01*
X-662950Y-536433D01*
X-663367Y-537133D01*
X-663700Y-538300D01*
X-663783Y-539350D01*
X-663617Y-540400D01*
X-663367Y-541100D01*
X-662867Y-541800D01*
X-662283Y-542267D01*
X-661700Y-542500D01*
X-661117D01*
X-660533Y-542267D01*
X-660033Y-541917D01*
X-659617Y-541450D01*
G01X-653233Y-542500D02*
X-656567D01*
Y-535500D01*
X-653233D01*
G01X-654567Y-538883D02*
X-656567D01*
G01X-649100Y-535500D02*
X-647100D01*
G01X-648100D02*
Y-542500D01*
G01X-649100D02*
X-647100D01*
G01X-643383Y-535500D02*
X-641300Y-542500D01*
X-639217Y-535500D01*
G01X-632833Y-542500D02*
X-636167D01*
Y-535500D01*
X-632833D01*
G01X-634167Y-538883D02*
X-636167D01*
G01X-629533Y-542500D02*
Y-535500D01*
X-627867D01*
X-627200Y-535850D01*
X-626700Y-536317D01*
X-626283Y-537017D01*
X-625950Y-537833D01*
X-625867Y-539000D01*
X-625950Y-540167D01*
X-626283Y-540983D01*
X-626700Y-541684D01*
X-627200Y-542150D01*
X-627867Y-542500D01*
X-629533D01*
G01X-615100Y-535500D02*
X-613100D01*
G01X-614100D02*
Y-542500D01*
G01X-615100D02*
X-613100D01*
G01X-609217D02*
Y-535500D01*
X-605383Y-542500D01*
Y-535500D01*
G01X-872500Y-520500D02*
Y-527500D01*
G01X-874417Y-520500D02*
X-870583D01*
G01X-867450Y-527500D02*
Y-520500D01*
G01X-863950D02*
Y-527500D01*
G01Y-524000D02*
X-867450D01*
G01X-857233Y-527500D02*
X-860567D01*
Y-520500D01*
X-857233D01*
G01X-858567Y-523883D02*
X-860567D01*
G01X-846967Y-527500D02*
Y-520500D01*
X-844967D01*
X-844300Y-520850D01*
X-843800Y-521667D01*
X-843633Y-522600D01*
X-843800Y-523533D01*
X-844217Y-524233D01*
X-844967Y-524584D01*
X-846967D01*
G01X-840167Y-527500D02*
Y-520500D01*
X-838083D01*
X-837417Y-520850D01*
X-837000Y-521317D01*
X-836833Y-522250D01*
X-837000Y-523183D01*
X-837500Y-523767D01*
X-838083Y-524117D01*
X-840167D01*
G01X-838083D02*
X-836833Y-527500D01*
G01X-831700D02*
X-832367Y-527383D01*
X-832950Y-526917D01*
X-833450Y-526217D01*
X-833783Y-525400D01*
X-833950Y-524467D01*
Y-523533D01*
X-833783Y-522600D01*
X-833450Y-521783D01*
X-832950Y-521083D01*
X-832367Y-520617D01*
X-831700Y-520500D01*
X-831033Y-520617D01*
X-830450Y-521083D01*
X-829950Y-521783D01*
X-829617Y-522600D01*
X-829450Y-523533D01*
Y-524467D01*
X-829617Y-525400D01*
X-829950Y-526217D01*
X-830450Y-526917D01*
X-831033Y-527383D01*
X-831700Y-527500D01*
G01X-826567D02*
Y-520500D01*
X-824567D01*
X-823900Y-520850D01*
X-823400Y-521667D01*
X-823233Y-522600D01*
X-823400Y-523533D01*
X-823817Y-524233D01*
X-824567Y-524584D01*
X-826567D01*
G01X-819767Y-527500D02*
Y-520500D01*
X-817683D01*
X-817017Y-520850D01*
X-816600Y-521317D01*
X-816433Y-522250D01*
X-816600Y-523183D01*
X-817100Y-523767D01*
X-817683Y-524117D01*
X-819767D01*
G01X-817683D02*
X-816433Y-527500D01*
G01X-812300Y-520500D02*
X-810300D01*
G01X-811300D02*
Y-527500D01*
G01X-812300D02*
X-810300D01*
G01X-802833D02*
X-806167D01*
Y-520500D01*
X-802833D01*
G01X-804167Y-523883D02*
X-806167D01*
G01X-797700Y-520500D02*
Y-527500D01*
G01X-799617Y-520500D02*
X-795783D01*
G01X-792983Y-527500D02*
X-790900Y-520500D01*
X-788817Y-527500D01*
G01X-789567Y-525050D02*
X-792233D01*
G01X-785767Y-527500D02*
Y-520500D01*
X-783683D01*
X-783017Y-520850D01*
X-782600Y-521317D01*
X-782433Y-522250D01*
X-782600Y-523183D01*
X-783100Y-523767D01*
X-783683Y-524117D01*
X-785767D01*
G01X-783683D02*
X-782433Y-527500D01*
G01X-777300D02*
Y-524350D01*
X-778967Y-520500D01*
G01X-775633D02*
X-777300Y-524350D01*
G01X-765367Y-527500D02*
Y-520500D01*
X-763367D01*
X-762700Y-520850D01*
X-762200Y-521667D01*
X-762033Y-522600D01*
X-762200Y-523533D01*
X-762617Y-524233D01*
X-763367Y-524584D01*
X-765367D01*
G01X-758567Y-527500D02*
Y-520500D01*
X-756483D01*
X-755817Y-520850D01*
X-755400Y-521317D01*
X-755233Y-522250D01*
X-755400Y-523183D01*
X-755900Y-523767D01*
X-756483Y-524117D01*
X-758567D01*
G01X-756483D02*
X-755233Y-527500D01*
G01X-750100D02*
X-750767Y-527383D01*
X-751350Y-526917D01*
X-751850Y-526217D01*
X-752183Y-525400D01*
X-752350Y-524467D01*
Y-523533D01*
X-752183Y-522600D01*
X-751850Y-521783D01*
X-751350Y-521083D01*
X-750767Y-520617D01*
X-750100Y-520500D01*
X-749433Y-520617D01*
X-748850Y-521083D01*
X-748350Y-521783D01*
X-748017Y-522600D01*
X-747850Y-523533D01*
Y-524467D01*
X-748017Y-525400D01*
X-748350Y-526217D01*
X-748850Y-526917D01*
X-749433Y-527383D01*
X-750100Y-527500D01*
G01X-744967D02*
Y-520500D01*
X-742967D01*
X-742300Y-520850D01*
X-741800Y-521667D01*
X-741633Y-522600D01*
X-741800Y-523533D01*
X-742217Y-524233D01*
X-742967Y-524584D01*
X-744967D01*
G01X-734833Y-527500D02*
X-738167D01*
Y-520500D01*
X-734833D01*
G01X-736167Y-523883D02*
X-738167D01*
G01X-731367Y-527500D02*
Y-520500D01*
X-729283D01*
X-728617Y-520850D01*
X-728200Y-521317D01*
X-728033Y-522250D01*
X-728200Y-523183D01*
X-728700Y-523767D01*
X-729283Y-524117D01*
X-731367D01*
G01X-729283D02*
X-728033Y-527500D01*
G01X-722900Y-520500D02*
Y-527500D01*
G01X-724817Y-520500D02*
X-720983D01*
G01X-716100Y-527500D02*
Y-524350D01*
X-717767Y-520500D01*
G01X-714433D02*
X-716100Y-524350D01*
G01X-702500Y-527500D02*
X-703167Y-527383D01*
X-703750Y-526917D01*
X-704250Y-526217D01*
X-704583Y-525400D01*
X-704750Y-524467D01*
Y-523533D01*
X-704583Y-522600D01*
X-704250Y-521783D01*
X-703750Y-521083D01*
X-703167Y-520617D01*
X-702500Y-520500D01*
X-701833Y-520617D01*
X-701250Y-521083D01*
X-700750Y-521783D01*
X-700417Y-522600D01*
X-700250Y-523533D01*
Y-524467D01*
X-700417Y-525400D01*
X-700750Y-526217D01*
X-701250Y-526917D01*
X-701833Y-527383D01*
X-702500Y-527500D01*
G01X-697283D02*
Y-520500D01*
X-694117D01*
G01X-695283Y-523883D02*
X-697283D01*
G01X-684267Y-527500D02*
Y-520500D01*
X-682100Y-526333D01*
X-679933Y-520500D01*
Y-527500D01*
G01X-676300Y-520500D02*
X-674300D01*
G01X-675300D02*
Y-527500D01*
G01X-676300D02*
X-674300D01*
G01X-666667Y-521083D02*
X-667167Y-520733D01*
X-667750Y-520500D01*
X-668417D01*
X-669167Y-520850D01*
X-669750Y-521433D01*
X-670167Y-522133D01*
X-670500Y-523300D01*
X-670583Y-524350D01*
X-670417Y-525400D01*
X-670167Y-526100D01*
X-669667Y-526800D01*
X-669083Y-527267D01*
X-668500Y-527500D01*
X-667917D01*
X-667333Y-527267D01*
X-666833Y-526917D01*
X-666417Y-526450D01*
G01X-663367Y-527500D02*
Y-520500D01*
X-661283D01*
X-660617Y-520850D01*
X-660200Y-521317D01*
X-660033Y-522250D01*
X-660200Y-523183D01*
X-660700Y-523767D01*
X-661283Y-524117D01*
X-663367D01*
G01X-661283D02*
X-660033Y-527500D01*
G01X-654900D02*
X-655567Y-527383D01*
X-656150Y-526917D01*
X-656650Y-526217D01*
X-656983Y-525400D01*
X-657150Y-524467D01*
Y-523533D01*
X-656983Y-522600D01*
X-656650Y-521783D01*
X-656150Y-521083D01*
X-655567Y-520617D01*
X-654900Y-520500D01*
X-654233Y-520617D01*
X-653650Y-521083D01*
X-653150Y-521783D01*
X-652817Y-522600D01*
X-652650Y-523533D01*
Y-524467D01*
X-652817Y-525400D01*
X-653150Y-526217D01*
X-653650Y-526917D01*
X-654233Y-527383D01*
X-654900Y-527500D01*
G01X-649850Y-526567D02*
X-649183Y-527150D01*
X-648433Y-527500D01*
X-647767D01*
X-647100Y-527150D01*
X-646600Y-526567D01*
X-646350Y-525750D01*
X-646517Y-524933D01*
X-646933Y-524233D01*
X-647683Y-523767D01*
X-648683Y-523533D01*
X-649267Y-523067D01*
X-649517Y-522250D01*
X-649350Y-521433D01*
X-648933Y-520850D01*
X-648350Y-520500D01*
X-647767D01*
X-647183Y-520733D01*
X-646683Y-521317D01*
G01X-641300Y-527500D02*
X-641967Y-527383D01*
X-642550Y-526917D01*
X-643050Y-526217D01*
X-643383Y-525400D01*
X-643550Y-524467D01*
Y-523533D01*
X-643383Y-522600D01*
X-643050Y-521783D01*
X-642550Y-521083D01*
X-641967Y-520617D01*
X-641300Y-520500D01*
X-640633Y-520617D01*
X-640050Y-521083D01*
X-639550Y-521783D01*
X-639217Y-522600D01*
X-639050Y-523533D01*
Y-524467D01*
X-639217Y-525400D01*
X-639550Y-526217D01*
X-640050Y-526917D01*
X-640633Y-527383D01*
X-641300Y-527500D01*
G01X-636083D02*
Y-520500D01*
X-632917D01*
G01X-634083Y-523883D02*
X-636083D01*
G01X-627700Y-520500D02*
Y-527500D01*
G01X-629617Y-520500D02*
X-625783D01*
G01X-872500Y-505500D02*
Y-512500D01*
G01X-874417Y-505500D02*
X-870583D01*
G01X-867450Y-512500D02*
Y-505500D01*
G01X-863950D02*
Y-512500D01*
G01Y-509000D02*
X-867450D01*
G01X-859900Y-505500D02*
X-857900D01*
G01X-858900D02*
Y-512500D01*
G01X-859900D02*
X-857900D01*
G01X-853850Y-511567D02*
X-853183Y-512150D01*
X-852433Y-512500D01*
X-851767D01*
X-851100Y-512150D01*
X-850600Y-511567D01*
X-850350Y-510750D01*
X-850517Y-509933D01*
X-850933Y-509233D01*
X-851683Y-508767D01*
X-852683Y-508533D01*
X-853267Y-508067D01*
X-853517Y-507250D01*
X-853350Y-506433D01*
X-852933Y-505850D01*
X-852350Y-505500D01*
X-851767D01*
X-851183Y-505733D01*
X-850683Y-506317D01*
G01X-840333Y-512500D02*
Y-505500D01*
X-838667D01*
X-838000Y-505850D01*
X-837500Y-506317D01*
X-837083Y-507017D01*
X-836750Y-507833D01*
X-836667Y-509000D01*
X-836750Y-510167D01*
X-837083Y-510983D01*
X-837500Y-511684D01*
X-838000Y-512150D01*
X-838667Y-512500D01*
X-840333D01*
G01X-833367D02*
Y-505500D01*
X-831283D01*
X-830617Y-505850D01*
X-830200Y-506317D01*
X-830033Y-507250D01*
X-830200Y-508183D01*
X-830700Y-508767D01*
X-831283Y-509117D01*
X-833367D01*
G01X-831283D02*
X-830033Y-512500D01*
G01X-826983D02*
X-824900Y-505500D01*
X-822817Y-512500D01*
G01X-823567Y-510050D02*
X-826233D01*
G01X-820600Y-505500D02*
X-819433Y-512500D01*
X-818100Y-505500D01*
X-816767Y-512500D01*
X-815600Y-505500D01*
G01X-812300D02*
X-810300D01*
G01X-811300D02*
Y-512500D01*
G01X-812300D02*
X-810300D01*
G01X-806417D02*
Y-505500D01*
X-802583Y-512500D01*
Y-505500D01*
G01X-797200Y-509000D02*
X-795533D01*
Y-511100D01*
X-796033Y-511800D01*
X-796617Y-512267D01*
X-797450Y-512500D01*
X-798283Y-512267D01*
X-798867Y-511800D01*
X-799367Y-511100D01*
X-799700Y-510283D01*
X-799867Y-509350D01*
Y-508533D01*
X-799700Y-507833D01*
X-799367Y-507017D01*
X-798867Y-506317D01*
X-798367Y-505850D01*
X-797700Y-505500D01*
X-797117D01*
X-796450Y-505733D01*
X-795950Y-506200D01*
G01X-782267Y-506083D02*
X-782767Y-505733D01*
X-783350Y-505500D01*
X-784017D01*
X-784767Y-505850D01*
X-785350Y-506433D01*
X-785767Y-507133D01*
X-786100Y-508300D01*
X-786183Y-509350D01*
X-786017Y-510400D01*
X-785767Y-511100D01*
X-785267Y-511800D01*
X-784683Y-512267D01*
X-784100Y-512500D01*
X-783517D01*
X-782933Y-512267D01*
X-782433Y-511917D01*
X-782017Y-511450D01*
G01X-777300Y-512500D02*
X-777967Y-512383D01*
X-778550Y-511917D01*
X-779050Y-511217D01*
X-779383Y-510400D01*
X-779550Y-509467D01*
Y-508533D01*
X-779383Y-507600D01*
X-779050Y-506783D01*
X-778550Y-506083D01*
X-777967Y-505617D01*
X-777300Y-505500D01*
X-776633Y-505617D01*
X-776050Y-506083D01*
X-775550Y-506783D01*
X-775217Y-507600D01*
X-775050Y-508533D01*
Y-509467D01*
X-775217Y-510400D01*
X-775550Y-511217D01*
X-776050Y-511917D01*
X-776633Y-512383D01*
X-777300Y-512500D01*
G01X-772417D02*
Y-505500D01*
X-768583Y-512500D01*
Y-505500D01*
G01X-763700D02*
Y-512500D01*
G01X-765617Y-505500D02*
X-761783D01*
G01X-758983Y-512500D02*
X-756900Y-505500D01*
X-754817Y-512500D01*
G01X-755567Y-510050D02*
X-758233D01*
G01X-751100Y-505500D02*
X-749100D01*
G01X-750100D02*
Y-512500D01*
G01X-751100D02*
X-749100D01*
G01X-745217D02*
Y-505500D01*
X-741383Y-512500D01*
Y-505500D01*
G01X-738250Y-511567D02*
X-737583Y-512150D01*
X-736833Y-512500D01*
X-736167D01*
X-735500Y-512150D01*
X-735000Y-511567D01*
X-734750Y-510750D01*
X-734917Y-509933D01*
X-735333Y-509233D01*
X-736083Y-508767D01*
X-737083Y-508533D01*
X-737667Y-508067D01*
X-737917Y-507250D01*
X-737750Y-506433D01*
X-737333Y-505850D01*
X-736750Y-505500D01*
X-736167D01*
X-735583Y-505733D01*
X-735083Y-506317D01*
G01X-723900Y-505500D02*
X-721900D01*
G01X-722900D02*
Y-512500D01*
G01X-723900D02*
X-721900D01*
G01X-718017D02*
Y-505500D01*
X-714183Y-512500D01*
Y-505500D01*
G01X-710883Y-512500D02*
Y-505500D01*
X-707717D01*
G01X-708883Y-508883D02*
X-710883D01*
G01X-702500Y-512500D02*
X-703167Y-512383D01*
X-703750Y-511917D01*
X-704250Y-511217D01*
X-704583Y-510400D01*
X-704750Y-509467D01*
Y-508533D01*
X-704583Y-507600D01*
X-704250Y-506783D01*
X-703750Y-506083D01*
X-703167Y-505617D01*
X-702500Y-505500D01*
X-701833Y-505617D01*
X-701250Y-506083D01*
X-700750Y-506783D01*
X-700417Y-507600D01*
X-700250Y-508533D01*
Y-509467D01*
X-700417Y-510400D01*
X-700750Y-511217D01*
X-701250Y-511917D01*
X-701833Y-512383D01*
X-702500Y-512500D01*
G01X-697367D02*
Y-505500D01*
X-695283D01*
X-694617Y-505850D01*
X-694200Y-506317D01*
X-694033Y-507250D01*
X-694200Y-508183D01*
X-694700Y-508767D01*
X-695283Y-509117D01*
X-697367D01*
G01X-695283D02*
X-694033Y-512500D01*
G01X-691067D02*
Y-505500D01*
X-688900Y-511333D01*
X-686733Y-505500D01*
Y-512500D01*
G01X-684183D02*
X-682100Y-505500D01*
X-680017Y-512500D01*
G01X-680767Y-510050D02*
X-683433D01*
G01X-675300Y-505500D02*
Y-512500D01*
G01X-677217Y-505500D02*
X-673383D01*
G01X-669500D02*
X-667500D01*
G01X-668500D02*
Y-512500D01*
G01X-669500D02*
X-667500D01*
G01X-661700D02*
X-662367Y-512383D01*
X-662950Y-511917D01*
X-663450Y-511217D01*
X-663783Y-510400D01*
X-663950Y-509467D01*
Y-508533D01*
X-663783Y-507600D01*
X-663450Y-506783D01*
X-662950Y-506083D01*
X-662367Y-505617D01*
X-661700Y-505500D01*
X-661033Y-505617D01*
X-660450Y-506083D01*
X-659950Y-506783D01*
X-659617Y-507600D01*
X-659450Y-508533D01*
Y-509467D01*
X-659617Y-510400D01*
X-659950Y-511217D01*
X-660450Y-511917D01*
X-661033Y-512383D01*
X-661700Y-512500D01*
G01X-656817D02*
Y-505500D01*
X-652983Y-512500D01*
Y-505500D01*
G01X-643800D02*
X-642633Y-512500D01*
X-641300Y-505500D01*
X-639967Y-512500D01*
X-638800Y-505500D01*
G01X-636250Y-512500D02*
Y-505500D01*
G01X-632750D02*
Y-512500D01*
G01Y-509000D02*
X-636250D01*
G01X-628700Y-505500D02*
X-626700D01*
G01X-627700D02*
Y-512500D01*
G01X-628700D02*
X-626700D01*
G01X-619067Y-506083D02*
X-619567Y-505733D01*
X-620150Y-505500D01*
X-620817D01*
X-621567Y-505850D01*
X-622150Y-506433D01*
X-622567Y-507133D01*
X-622900Y-508300D01*
X-622983Y-509350D01*
X-622817Y-510400D01*
X-622567Y-511100D01*
X-622067Y-511800D01*
X-621483Y-512267D01*
X-620900Y-512500D01*
X-620317D01*
X-619733Y-512267D01*
X-619233Y-511917D01*
X-618817Y-511450D01*
G01X-615850Y-512500D02*
Y-505500D01*
G01X-612350D02*
Y-512500D01*
G01Y-509000D02*
X-615850D01*
G01X-601500Y-505500D02*
X-599500D01*
G01X-600500D02*
Y-512500D01*
G01X-601500D02*
X-599500D01*
G01X-595450Y-511567D02*
X-594783Y-512150D01*
X-594033Y-512500D01*
X-593367D01*
X-592700Y-512150D01*
X-592200Y-511567D01*
X-591950Y-510750D01*
X-592117Y-509933D01*
X-592533Y-509233D01*
X-593283Y-508767D01*
X-594283Y-508533D01*
X-594867Y-508067D01*
X-595117Y-507250D01*
X-594950Y-506433D01*
X-594533Y-505850D01*
X-593950Y-505500D01*
X-593367D01*
X-592783Y-505733D01*
X-592283Y-506317D01*
G01X-858133Y-452500D02*
Y-445500D01*
X-856467D01*
X-855800Y-445850D01*
X-855300Y-446317D01*
X-854883Y-447017D01*
X-854550Y-447833D01*
X-854467Y-449000D01*
X-854550Y-450167D01*
X-854883Y-450983D01*
X-855300Y-451684D01*
X-855800Y-452150D01*
X-856467Y-452500D01*
X-858133D01*
G01X-847833D02*
X-851167D01*
Y-445500D01*
X-847833D01*
G01X-849167Y-448883D02*
X-851167D01*
G01X-844450Y-451567D02*
X-843783Y-452150D01*
X-843033Y-452500D01*
X-842367D01*
X-841700Y-452150D01*
X-841200Y-451567D01*
X-840950Y-450750D01*
X-841117Y-449933D01*
X-841533Y-449233D01*
X-842283Y-448767D01*
X-843283Y-448533D01*
X-843867Y-448067D01*
X-844117Y-447250D01*
X-843950Y-446433D01*
X-843533Y-445850D01*
X-842950Y-445500D01*
X-842367D01*
X-841783Y-445733D01*
X-841283Y-446317D01*
G01X-836900Y-445500D02*
X-834900D01*
G01X-835900D02*
Y-452500D01*
G01X-836900D02*
X-834900D01*
G01X-828600Y-449000D02*
X-826933D01*
Y-451100D01*
X-827433Y-451800D01*
X-828017Y-452267D01*
X-828850Y-452500D01*
X-829683Y-452267D01*
X-830267Y-451800D01*
X-830767Y-451100D01*
X-831100Y-450283D01*
X-831267Y-449350D01*
Y-448533D01*
X-831100Y-447833D01*
X-830767Y-447017D01*
X-830267Y-446317D01*
X-829767Y-445850D01*
X-829100Y-445500D01*
X-828517D01*
X-827850Y-445733D01*
X-827350Y-446200D01*
G01X-824217Y-452500D02*
Y-445500D01*
X-820383Y-452500D01*
Y-445500D01*
G01X-813833Y-452500D02*
X-817167D01*
Y-445500D01*
X-813833D01*
G01X-815167Y-448883D02*
X-817167D01*
G01X-810367Y-452500D02*
Y-445500D01*
X-808283D01*
X-807617Y-445850D01*
X-807200Y-446317D01*
X-807033Y-447250D01*
X-807200Y-448183D01*
X-807700Y-448767D01*
X-808283Y-449117D01*
X-810367D01*
G01X-808283D02*
X-807033Y-452500D01*
G01X-858133D02*
Y-445500D01*
X-856467D01*
X-855800Y-445850D01*
X-855300Y-446317D01*
X-854883Y-447017D01*
X-854550Y-447833D01*
X-854467Y-449000D01*
X-854550Y-450167D01*
X-854883Y-450983D01*
X-855300Y-451684D01*
X-855800Y-452150D01*
X-856467Y-452500D01*
X-858133D01*
G01X-847833D02*
X-851167D01*
Y-445500D01*
X-847833D01*
G01X-849167Y-448883D02*
X-851167D01*
G01X-844450Y-451567D02*
X-843783Y-452150D01*
X-843033Y-452500D01*
X-842367D01*
X-841700Y-452150D01*
X-841200Y-451567D01*
X-840950Y-450750D01*
X-841117Y-449933D01*
X-841533Y-449233D01*
X-842283Y-448767D01*
X-843283Y-448533D01*
X-843867Y-448067D01*
X-844117Y-447250D01*
X-843950Y-446433D01*
X-843533Y-445850D01*
X-842950Y-445500D01*
X-842367D01*
X-841783Y-445733D01*
X-841283Y-446317D01*
G01X-836900Y-445500D02*
X-834900D01*
G01X-835900D02*
Y-452500D01*
G01X-836900D02*
X-834900D01*
G01X-828600Y-449000D02*
X-826933D01*
Y-451100D01*
X-827433Y-451800D01*
X-828017Y-452267D01*
X-828850Y-452500D01*
X-829683Y-452267D01*
X-830267Y-451800D01*
X-830767Y-451100D01*
X-831100Y-450283D01*
X-831267Y-449350D01*
Y-448533D01*
X-831100Y-447833D01*
X-830767Y-447017D01*
X-830267Y-446317D01*
X-829767Y-445850D01*
X-829100Y-445500D01*
X-828517D01*
X-827850Y-445733D01*
X-827350Y-446200D01*
G01X-824217Y-452500D02*
Y-445500D01*
X-820383Y-452500D01*
Y-445500D01*
G01X-813833Y-452500D02*
X-817167D01*
Y-445500D01*
X-813833D01*
G01X-815167Y-448883D02*
X-817167D01*
G01X-810367Y-452500D02*
Y-445500D01*
X-808283D01*
X-807617Y-445850D01*
X-807200Y-446317D01*
X-807033Y-447250D01*
X-807200Y-448183D01*
X-807700Y-448767D01*
X-808283Y-449117D01*
X-810367D01*
G01X-808283D02*
X-807033Y-452500D01*
G01X-642033Y-455000D02*
Y-448000D01*
X-640367D01*
X-639700Y-448350D01*
X-639200Y-448817D01*
X-638783Y-449517D01*
X-638450Y-450333D01*
X-638367Y-451500D01*
X-638450Y-452667D01*
X-638783Y-453483D01*
X-639200Y-454184D01*
X-639700Y-454650D01*
X-640367Y-455000D01*
X-642033D01*
G01X-635483D02*
X-633400Y-448000D01*
X-631317Y-455000D01*
G01X-632067Y-452550D02*
X-634733D01*
G01X-626600Y-448000D02*
Y-455000D01*
G01X-628517Y-448000D02*
X-624683D01*
G01X-618133Y-455000D02*
X-621467D01*
Y-448000D01*
X-618133D01*
G01X-619467Y-451383D02*
X-621467D01*
G54D16*
X-1122128Y-170650D03*
Y-175150D03*
X-1121800Y-180000D03*
X-1127689Y-179900D03*
X-1131311D03*
X-1118528Y-170650D03*
Y-175150D03*
X-1118200Y-180000D03*
X-1099028Y-175150D03*
X-1102628D03*
X-1099028Y-170650D03*
X-1102628D03*
X-1099028Y-179650D03*
X-1102628D03*
X-1088489Y-179700D03*
X-1092111D03*
X-1050800Y-29400D03*
X-1047200D03*
X-1047289Y-23000D03*
X-1050911D03*
X-1050800Y-5400D03*
X-1047200D03*
X-1047189Y0D03*
X-1050811D03*
X-257889Y-180000D03*
X-261511D03*
X-252050Y-170650D03*
X-248450D03*
X-252050Y-175150D03*
X-248450D03*
X-248100Y-180000D03*
X-251700D03*
X-228950Y-175150D03*
X-232550D03*
X-228950Y-170650D03*
X-232550D03*
X-228950Y-179650D03*
X-232550D03*
X-222011Y-179900D03*
X-218389D03*
X-179950Y-29850D03*
X-176350D03*
X-176389Y-24500D03*
X-180011D03*
X-178800Y-4500D03*
X-175200D03*
X-175189Y1000D03*
X-178811D03*
G54D26*
G01X-1020800Y-457700D02*
G02X-1020300Y-458200I0J-500D01*
G01Y-458400D01*
G02X-1020900Y-459000I-600J0D01*
G01X-1021300D01*
G01X-1021800Y-460500D02*
Y-457700D01*
X-1020600D01*
G01X-1018340Y-459100D02*
G03I-2660J0D01*
G01X-1020700D02*
X-1020200Y-460500D01*
G54D17*
X-1120276Y-142362D03*
X-1123425D03*
X-1126575D03*
X-1128150Y-110079D03*
X-1125000D03*
X-1121850D03*
X-1104528Y-142362D03*
X-1107677D03*
X-1110827D03*
X-1113976D03*
X-1117126D03*
X-1118701Y-110079D03*
X-1115551D03*
X-1112402D03*
X-1109252D03*
X-1106102D03*
X-1098228Y-142362D03*
X-1101378D03*
X-1102953Y-110079D03*
X-1099803D03*
X-256496Y-142362D03*
X-258071Y-110079D03*
X-254921D03*
X-240748Y-142362D03*
X-243898D03*
X-247047D03*
X-250197D03*
X-253346D03*
X-251772Y-110079D03*
X-248622D03*
X-245472D03*
X-242323D03*
X-239173D03*
X-228150Y-142362D03*
X-231299D03*
X-234449D03*
X-237598D03*
X-236024Y-110079D03*
X-232874D03*
X-229724D03*
G54D18*
G01X-1184000Y-502500D02*
Y-512500D01*
G01X-1186683Y-502500D02*
X-1181317D01*
G01X-1176833Y-512500D02*
Y-502500D01*
X-1173917D01*
X-1172983Y-503000D01*
X-1172400Y-503667D01*
X-1172167Y-505000D01*
X-1172400Y-506333D01*
X-1173100Y-507167D01*
X-1173917Y-507667D01*
X-1176833D01*
G01X-1173917D02*
X-1172167Y-512500D01*
G01X-1167917D02*
X-1165000Y-502500D01*
X-1162083Y-512500D01*
G01X-1163133Y-509000D02*
X-1166867D01*
G01X-1155500Y-512500D02*
Y-508000D01*
X-1157833Y-502500D01*
G01X-1153167D02*
X-1155500Y-508000D01*
G01X-1135567Y-507167D02*
X-1135100Y-506667D01*
X-1134750Y-505834D01*
X-1134517Y-504667D01*
X-1134750Y-503667D01*
X-1135217Y-503000D01*
X-1136033Y-502500D01*
X-1139183D01*
Y-512500D01*
X-1135333D01*
X-1134517Y-511833D01*
X-1134050Y-510833D01*
X-1133817Y-509667D01*
X-1134050Y-508500D01*
X-1134750Y-507500D01*
X-1135567Y-507167D01*
X-1139183D01*
G01X-1129917Y-512500D02*
X-1127000Y-502500D01*
X-1124083Y-512500D01*
G01X-1125133Y-509000D02*
X-1128867D01*
G01X-1114933Y-503333D02*
X-1115633Y-502833D01*
X-1116450Y-502500D01*
X-1117383D01*
X-1118433Y-503000D01*
X-1119250Y-503833D01*
X-1119833Y-504833D01*
X-1120300Y-506500D01*
X-1120417Y-508000D01*
X-1120183Y-509500D01*
X-1119833Y-510500D01*
X-1119133Y-511500D01*
X-1118317Y-512167D01*
X-1117500Y-512500D01*
X-1116683D01*
X-1115867Y-512167D01*
X-1115167Y-511667D01*
X-1114583Y-511000D01*
G01X-1110567Y-512500D02*
Y-502500D01*
G01X-1106133D02*
X-1110567Y-508667D01*
G01X-1105433Y-512500D02*
X-1108583Y-505834D01*
G01X-1100833Y-512500D02*
Y-502500D01*
X-1098033D01*
X-1097100Y-503000D01*
X-1096400Y-504167D01*
X-1096167Y-505500D01*
X-1096400Y-506833D01*
X-1096983Y-507833D01*
X-1098033Y-508334D01*
X-1100833D01*
G01X-1091333Y-502500D02*
Y-512500D01*
X-1086667D01*
G01X-1082417D02*
X-1079500Y-502500D01*
X-1076583Y-512500D01*
G01X-1077633Y-509000D02*
X-1081367D01*
G01X-1072683Y-512500D02*
Y-502500D01*
X-1067317Y-512500D01*
Y-502500D01*
G01X-1058167Y-512500D02*
X-1062833D01*
Y-502500D01*
X-1058167D01*
G01X-1060033Y-507333D02*
X-1062833D01*
G01X-1043717Y-512500D02*
Y-502500D01*
X-1039283D01*
G01X-1040917Y-507333D02*
X-1043717D01*
G01X-1034917Y-512500D02*
X-1032000Y-502500D01*
X-1029083Y-512500D01*
G01X-1030133Y-509000D02*
X-1033867D01*
G01X-1021567Y-507167D02*
X-1021100Y-506667D01*
X-1020750Y-505834D01*
X-1020517Y-504667D01*
X-1020750Y-503667D01*
X-1021217Y-503000D01*
X-1022033Y-502500D01*
X-1025183D01*
Y-512500D01*
X-1021333D01*
X-1020517Y-511833D01*
X-1020050Y-510833D01*
X-1019817Y-509667D01*
X-1020050Y-508500D01*
X-1020750Y-507500D01*
X-1021567Y-507167D01*
X-1025183D01*
G01X-1002567D02*
X-1002100Y-506667D01*
X-1001750Y-505834D01*
X-1001517Y-504667D01*
X-1001750Y-503667D01*
X-1002217Y-503000D01*
X-1003033Y-502500D01*
X-1006183D01*
Y-512500D01*
X-1002333D01*
X-1001517Y-511833D01*
X-1001050Y-510833D01*
X-1000817Y-509667D01*
X-1001050Y-508500D01*
X-1001750Y-507500D01*
X-1002567Y-507167D01*
X-1006183D01*
G01X-985083Y-515833D02*
X-986250Y-514167D01*
X-986833Y-512500D01*
Y-505834D01*
X-986250Y-504167D01*
X-985083Y-502500D01*
G01X-975000Y-512500D02*
X-975933Y-512333D01*
X-976750Y-511667D01*
X-977450Y-510667D01*
X-977917Y-509500D01*
X-978150Y-508167D01*
Y-506833D01*
X-977917Y-505500D01*
X-977450Y-504333D01*
X-976750Y-503333D01*
X-975933Y-502667D01*
X-975000Y-502500D01*
X-974067Y-502667D01*
X-973250Y-503333D01*
X-972550Y-504333D01*
X-972083Y-505500D01*
X-971850Y-506833D01*
Y-508167D01*
X-972083Y-509500D01*
X-972550Y-510667D01*
X-973250Y-511667D01*
X-974067Y-512333D01*
X-975000Y-512500D01*
G01X-967950Y-511167D02*
X-967017Y-512000D01*
X-965967Y-512500D01*
X-965033D01*
X-964100Y-512000D01*
X-963400Y-511167D01*
X-963050Y-510000D01*
X-963283Y-508834D01*
X-963867Y-507833D01*
X-964917Y-507167D01*
X-966317Y-506833D01*
X-967133Y-506167D01*
X-967483Y-505000D01*
X-967250Y-503833D01*
X-966667Y-503000D01*
X-965850Y-502500D01*
X-965033D01*
X-964217Y-502833D01*
X-963517Y-503667D01*
G01X-958333Y-512500D02*
Y-502500D01*
X-955533D01*
X-954600Y-503000D01*
X-953900Y-504167D01*
X-953667Y-505500D01*
X-953900Y-506833D01*
X-954483Y-507833D01*
X-955533Y-508334D01*
X-958333D01*
G01X-945917Y-515833D02*
X-944750Y-514167D01*
X-944167Y-512500D01*
Y-505834D01*
X-944750Y-504167D01*
X-945917Y-502500D01*
G01X-902000Y-470000D02*
Y-460000D01*
X-903400Y-462000D01*
G01Y-470000D02*
X-900600D01*
G01X-892500Y-470333D02*
X-892733Y-470167D01*
Y-469833D01*
X-892500Y-469667D01*
X-892267Y-469833D01*
Y-470167D01*
X-892500Y-470333D01*
G01Y-465834D02*
X-892733Y-465667D01*
Y-465333D01*
X-892500Y-465167D01*
X-892267Y-465333D01*
Y-465667D01*
X-892500Y-465834D01*
G01X-883000Y-470000D02*
Y-460000D01*
X-884400Y-462000D01*
G01Y-470000D02*
X-881600D01*
G01X-785060Y-472187D02*
X-784127Y-473020D01*
X-783077Y-473520D01*
X-782143D01*
X-781210Y-473020D01*
X-780510Y-472187D01*
X-780160Y-471020D01*
X-780393Y-469854D01*
X-780977Y-468853D01*
X-782027Y-468187D01*
X-783427Y-467853D01*
X-784243Y-467187D01*
X-784593Y-466020D01*
X-784360Y-464853D01*
X-783777Y-464020D01*
X-782960Y-463520D01*
X-782143D01*
X-781327Y-463853D01*
X-780627Y-464687D01*
G01X-775560Y-473520D02*
Y-463520D01*
G01X-770660D02*
Y-473520D01*
G01Y-468520D02*
X-775560D01*
G01X-766527Y-473520D02*
X-763610Y-463520D01*
X-760693Y-473520D01*
G01X-761743Y-470020D02*
X-765477D01*
G01X-757610Y-463520D02*
X-755977Y-473520D01*
X-754110Y-463520D01*
X-752243Y-473520D01*
X-750610Y-463520D01*
G01X-668067Y-470500D02*
X-667367Y-471667D01*
X-666433Y-472333D01*
X-665383Y-472500D01*
X-664450Y-472333D01*
X-663517Y-471500D01*
X-662933Y-470500D01*
X-662817Y-469500D01*
X-663050Y-468334D01*
X-663867Y-467500D01*
X-664683Y-467167D01*
X-665733D01*
G01X-664683D02*
X-663983Y-466667D01*
X-663400Y-465834D01*
X-663167Y-464833D01*
X-663400Y-463833D01*
X-663983Y-463000D01*
X-665033Y-462500D01*
X-666083Y-462667D01*
X-667133Y-463333D01*
G01X-656000Y-462500D02*
X-656933Y-462833D01*
X-657633Y-463667D01*
X-658100Y-464667D01*
X-658450Y-466000D01*
X-658567Y-467500D01*
X-658450Y-469000D01*
X-658100Y-470333D01*
X-657633Y-471334D01*
X-656933Y-472167D01*
X-656000Y-472500D01*
X-655067Y-472167D01*
X-654367Y-471334D01*
X-653900Y-470333D01*
X-653550Y-469000D01*
X-653433Y-467500D01*
X-653550Y-466000D01*
X-653900Y-464667D01*
X-654367Y-463667D01*
X-655067Y-462833D01*
X-656000Y-462500D01*
G01X-648017Y-469167D02*
X-644983D01*
G01X-639917Y-472500D02*
X-637000Y-462500D01*
X-634083Y-472500D01*
G01X-635133Y-469000D02*
X-638867D01*
G01X-629833Y-472500D02*
Y-462500D01*
X-627033D01*
X-626100Y-463000D01*
X-625400Y-464167D01*
X-625167Y-465500D01*
X-625400Y-466833D01*
X-625983Y-467833D01*
X-627033Y-468334D01*
X-629833D01*
G01X-620333Y-472500D02*
Y-462500D01*
X-617417D01*
X-616483Y-463000D01*
X-615900Y-463667D01*
X-615667Y-465000D01*
X-615900Y-466333D01*
X-616600Y-467167D01*
X-617417Y-467667D01*
X-620333D01*
G01X-617417D02*
X-615667Y-472500D01*
G01X-610017Y-469167D02*
X-606983D01*
G01X-599000Y-472500D02*
Y-462500D01*
X-600400Y-464500D01*
G01Y-472500D02*
X-597600D01*
G01X-588100D02*
Y-462500D01*
X-592417Y-469667D01*
X-586583D01*
G54D19*
G01X-1174900Y-473500D02*
X-1171300Y-466100D01*
X-1171800Y-465700D01*
X-1175900Y-473200D01*
X-1176200Y-471200D01*
X-1172500Y-465400D01*
X-1175700Y-471300D01*
X-1176500Y-469800D01*
X-1172900Y-464900D01*
X-1173600Y-451800D01*
X-1173700Y-449900D01*
X-1182100D01*
X-1187400Y-473000D01*
X-1182400D01*
X-1177800Y-456000D01*
X-1177000Y-455900D01*
X-1176100Y-468500D01*
X-1173700Y-464500D01*
X-1174600Y-450800D01*
X-1181500Y-450900D01*
X-1186400Y-472100D01*
X-1183100D01*
X-1178300Y-454800D01*
X-1176600Y-455000D01*
X-1175500Y-466300D01*
X-1174600Y-464300D01*
X-1175400Y-451700D01*
X-1181000Y-451800D01*
X-1185300Y-471300D01*
X-1183800Y-471400D01*
X-1179000Y-454300D01*
X-1176200D01*
X-1175200Y-462200D01*
X-1176200Y-452500D01*
X-1180500Y-452800D01*
X-1184300Y-470600D01*
X-1179700Y-453400D01*
X-1176800D01*
G01X-1182820Y-448900D02*
X-1188360Y-473900D01*
X-1181580D01*
X-1177300Y-456700D01*
X-1176920Y-473900D01*
X-1172260D01*
X-1163400Y-456920D01*
X-1167240Y-473900D01*
X-1160380D01*
X-1154840Y-448900D01*
X-1164540D01*
X-1172540Y-464820D01*
X-1172880Y-448900D01*
X-1182820D01*
G01X-1155800Y-449500D02*
X-1161100Y-472900D01*
X-1166100Y-473000D01*
X-1166000Y-471900D01*
X-1161800Y-472100D01*
X-1161300Y-471000D01*
X-1165900Y-471100D01*
X-1165700Y-470000D01*
X-1161300D01*
X-1160800Y-469200D01*
X-1165300Y-469100D01*
X-1165200Y-468100D01*
X-1160700D01*
X-1160400Y-467100D01*
X-1165100Y-467200D01*
X-1164900Y-466300D01*
X-1160300Y-466200D01*
X-1160000Y-465200D01*
X-1164700Y-465300D01*
X-1164400Y-464200D01*
X-1159700Y-464300D01*
X-1159300Y-463100D01*
X-1164700Y-463500D01*
X-1164000Y-462500D01*
X-1159500Y-462600D01*
X-1159000Y-461700D01*
X-1163900D01*
X-1163600Y-460600D01*
X-1159100Y-460800D01*
X-1158800Y-459900D01*
X-1163200D01*
X-1163100Y-459200D01*
X-1158800D01*
X-1158300Y-458500D01*
X-1163000Y-458400D01*
X-1162900Y-457800D01*
X-1158400Y-457900D01*
X-1158200Y-457200D01*
X-1162500Y-457000D01*
X-1163100Y-456500D01*
X-1157800D01*
X-1157500Y-455500D01*
X-1156600Y-449800D01*
X-1164000D01*
X-1164500Y-450700D01*
X-1157600D01*
X-1157800Y-451700D01*
X-1165000Y-451600D01*
X-1165400Y-452400D01*
X-1157900Y-452500D01*
X-1157800Y-453500D01*
X-1165900Y-453200D01*
X-1166200Y-453900D01*
X-1158000Y-454300D01*
X-1158300Y-455300D01*
X-1166600Y-454800D01*
X-1158900Y-455900D01*
X-1167000Y-455600D01*
X-1163500Y-456400D01*
X-1167300Y-456300D01*
X-1171700Y-465200D01*
X-1169200Y-466400D01*
X-1164500Y-457200D01*
X-1166900Y-457100D01*
X-1170600Y-465200D01*
X-1169500Y-465500D01*
X-1166000Y-457800D01*
G01X-1170300Y-466300D02*
X-1174000Y-473600D01*
G01X-1169500Y-466900D02*
X-1172800Y-473000D01*
G01X-1152800Y-456400D02*
X-1156600Y-473100D01*
X-1152200Y-473000D01*
X-1148300Y-456600D01*
X-1149500D01*
X-1152900Y-472000D01*
X-1155600Y-472300D01*
X-1152100Y-456500D01*
X-1150400Y-456400D01*
X-1153600Y-471200D01*
X-1154500Y-471400D01*
X-1151400Y-457200D01*
G01X-1153420Y-455700D02*
X-1157540Y-473900D01*
X-1151380D01*
X-1147440Y-455700D01*
X-1153420D01*
G01X-1151600Y-450100D02*
X-1146700Y-450000D01*
X-1147000Y-451000D01*
X-1151700D01*
G01X-1152020Y-448900D02*
X-1152660Y-451900D01*
X-1146380D01*
X-1145740Y-448900D01*
X-1152020D01*
G01X-1129400Y-468900D02*
X-1131800Y-471900D01*
X-1136500Y-473700D01*
X-1142100Y-473600D01*
X-1144600Y-472300D01*
X-1145800Y-471000D01*
X-1146400Y-469500D01*
X-1146700Y-467600D01*
X-1146500Y-464600D01*
X-1145400Y-461200D01*
X-1143500Y-459100D01*
X-1140200Y-456900D01*
X-1136100Y-456200D01*
X-1132300Y-456400D01*
X-1129400Y-457900D01*
X-1127500Y-460900D01*
X-1132500Y-461000D01*
X-1133400Y-459200D01*
X-1135100Y-458100D01*
X-1136800Y-458000D01*
X-1138600Y-458900D01*
X-1140300Y-460700D01*
X-1141800Y-463600D01*
X-1142400Y-466600D01*
X-1141500Y-470400D01*
X-1140200Y-471500D01*
X-1138300Y-471600D01*
X-1136300Y-471400D01*
X-1134500Y-469100D01*
X-1130300Y-469000D01*
X-1132500Y-471200D01*
X-1134900Y-472000D01*
X-1137200Y-472800D01*
X-1142300Y-472700D01*
X-1144900Y-470600D01*
X-1145800Y-467400D01*
X-1145500Y-465100D01*
X-1144700Y-462000D01*
X-1143300Y-460200D01*
X-1139800Y-457700D01*
X-1135400Y-457000D01*
X-1131300Y-457600D01*
X-1128800Y-460100D01*
X-1132100D01*
X-1134300Y-457900D01*
X-1130100Y-458800D01*
X-1129500Y-459400D01*
X-1132600Y-459000D01*
G01X-1133300Y-461900D02*
Y-461420D01*
X-1133640Y-460240D01*
X-1134300Y-459200D01*
X-1135200Y-458900D01*
X-1136580D01*
X-1138060Y-459820D01*
X-1139360Y-461000D01*
X-1140240Y-462220D01*
X-1140880Y-463920D01*
X-1141300Y-465380D01*
X-1141500Y-467060D01*
Y-468020D01*
X-1141020Y-469220D01*
X-1139780Y-470700D01*
X-1137160D01*
X-1135840Y-469500D01*
X-1134980Y-468200D01*
X-1134940Y-468100D01*
X-1128180D01*
X-1128240Y-468240D01*
X-1128840Y-469340D01*
X-1129020Y-469800D01*
X-1129740Y-470700D01*
X-1130500Y-471460D01*
X-1131660Y-472420D01*
X-1132820Y-473200D01*
X-1133740Y-473740D01*
X-1136380Y-474500D01*
X-1141640D01*
X-1142540Y-474320D01*
X-1144220Y-473760D01*
X-1144900Y-473240D01*
X-1146240Y-471900D01*
X-1146780Y-471180D01*
X-1146940Y-470880D01*
X-1147320Y-469660D01*
X-1147500Y-468640D01*
Y-464780D01*
X-1146940Y-462540D01*
X-1146380Y-461580D01*
X-1145980Y-460780D01*
X-1145420Y-459880D01*
X-1143700Y-458140D01*
X-1142740Y-457380D01*
X-1142000Y-456820D01*
X-1140240Y-456040D01*
X-1139500Y-455660D01*
X-1138800Y-455480D01*
X-1137260Y-455300D01*
X-1134320D01*
X-1132020Y-455500D01*
X-1130940Y-455860D01*
X-1130580Y-456020D01*
X-1129260Y-456780D01*
X-1128940Y-457100D01*
X-1127820Y-458420D01*
X-1127060Y-460300D01*
X-1126900Y-460800D01*
Y-461900D01*
X-1133300D01*
G01X-1137900Y-458000D02*
X-1140300Y-459100D01*
X-1142500Y-460900D01*
X-1143900Y-462600D01*
X-1144800Y-467600D01*
X-1144200Y-470000D01*
X-1141000Y-472300D01*
X-1136400Y-472200D01*
X-1131600Y-469600D01*
X-1135400Y-470400D01*
X-1141100Y-471400D01*
X-1142100Y-470700D01*
X-1142700Y-469000D01*
X-1143100Y-467100D01*
X-1142700Y-464100D01*
X-1140500Y-459900D01*
X-1143400Y-463700D01*
X-1143600Y-465700D01*
X-1143900Y-467700D01*
X-1143000Y-469900D01*
G01X-1113500Y-459200D02*
X-1123500Y-459300D01*
X-1123700Y-460100D01*
X-1114300Y-460000D01*
X-1116500Y-460800D01*
X-1124200Y-461000D01*
X-1124400Y-461900D01*
X-1117600Y-461800D01*
X-1118800Y-462800D01*
X-1124500Y-462700D01*
X-1124600Y-463600D01*
X-1119300Y-463700D01*
X-1120100Y-464800D01*
X-1125000Y-464600D01*
Y-465500D01*
X-1120600Y-465700D01*
X-1120800Y-466700D01*
X-1125300Y-466500D01*
X-1125500Y-467400D01*
X-1121000Y-467600D01*
X-1121200Y-468700D01*
X-1125600Y-468400D01*
X-1125900Y-469100D01*
X-1121500Y-469500D01*
X-1121700Y-470700D01*
X-1126100Y-470000D01*
X-1126200Y-470700D01*
X-1121900Y-471200D01*
X-1122100Y-472000D01*
X-1126300Y-471700D01*
X-1126700Y-472300D01*
X-1122100Y-472700D01*
X-1122200Y-473100D01*
X-1126800Y-473200D01*
G01X-1114060Y-460760D02*
X-1114840Y-460920D01*
X-1115740Y-461140D01*
X-1116880Y-461820D01*
X-1117700Y-462640D01*
X-1118620Y-463340D01*
X-1118840Y-464020D01*
X-1119440Y-464820D01*
X-1119660Y-465480D01*
X-1120060Y-466280D01*
X-1120280Y-466960D01*
X-1120480Y-468360D01*
X-1120680Y-468940D01*
X-1120880Y-469940D01*
X-1121080Y-470540D01*
X-1121700Y-472980D01*
X-1121820Y-473900D01*
X-1127640D01*
X-1126920Y-471060D01*
X-1126720Y-470440D01*
X-1126500Y-468800D01*
X-1126320Y-467860D01*
X-1126120Y-467260D01*
X-1125920Y-466260D01*
X-1125720Y-465660D01*
X-1125300Y-464000D01*
X-1125120Y-462220D01*
X-1124920Y-461660D01*
X-1124720Y-460660D01*
X-1124520Y-460060D01*
X-1123720Y-456800D01*
X-1123580Y-455700D01*
X-1117880D01*
X-1118100Y-456160D01*
Y-458740D01*
X-1116500Y-457160D01*
X-1115780Y-456620D01*
X-1114680Y-456060D01*
X-1113560Y-455680D01*
X-1112460Y-455500D01*
X-1111720D01*
X-1112460Y-458440D01*
X-1114060Y-460760D01*
G01X-1123100Y-456500D02*
X-1118900Y-456600D01*
X-1118800Y-457600D01*
X-1123100Y-457500D01*
X-1123300Y-458500D01*
X-1113100Y-458400D01*
X-1112600Y-456400D01*
X-1116100Y-457600D01*
X-1113500D01*
G01X-1105100Y-471100D02*
X-1104060D01*
X-1103780Y-470820D01*
X-1103200Y-470640D01*
X-1102080Y-469740D01*
X-1100800Y-468240D01*
X-1100380Y-467400D01*
X-1100180Y-467100D01*
X-1099960Y-466660D01*
X-1099540Y-465720D01*
X-1099320Y-465060D01*
X-1099100Y-464180D01*
Y-461220D01*
X-1099360Y-460200D01*
X-1099660Y-459900D01*
X-1100700Y-458640D01*
X-1101220Y-458300D01*
X-1103340D01*
X-1103700Y-458640D01*
X-1105300Y-459840D01*
X-1105760Y-460320D01*
X-1106180Y-460940D01*
X-1107060Y-462020D01*
X-1107260Y-462880D01*
X-1107660Y-463660D01*
X-1108100Y-465000D01*
Y-468640D01*
X-1107620Y-469600D01*
X-1107140Y-470340D01*
X-1105980Y-471100D01*
X-1105100D01*
G01X-1112540Y-460460D02*
X-1110680Y-458140D01*
X-1109940Y-457580D01*
X-1109000Y-456840D01*
X-1108480Y-456660D01*
X-1107940Y-456400D01*
X-1107740Y-456200D01*
X-1107480Y-456060D01*
X-1106880Y-455860D01*
X-1106480Y-455660D01*
X-1105960Y-455480D01*
X-1104600Y-455300D01*
X-1103440Y-455100D01*
X-1100940D01*
X-1098240Y-455480D01*
X-1097720Y-455660D01*
X-1097020Y-456020D01*
X-1096180Y-456640D01*
X-1095620Y-456820D01*
X-1095540Y-456900D01*
X-1094200Y-458440D01*
X-1093660Y-459520D01*
X-1093460Y-460100D01*
X-1093100Y-461020D01*
Y-464400D01*
X-1093420Y-465360D01*
X-1094300Y-465520D01*
X-1094720Y-465740D01*
X-1095320Y-465940D01*
X-1096120Y-466340D01*
X-1096720Y-466540D01*
X-1097100Y-466720D01*
X-1098100Y-466920D01*
X-1098520Y-467140D01*
X-1099160Y-467360D01*
X-1101180Y-468700D01*
X-1094660D01*
X-1095220Y-469800D01*
X-1095560Y-470320D01*
X-1097480Y-472220D01*
X-1099940Y-473740D01*
X-1102580Y-474500D01*
X-1108800D01*
X-1109300Y-474340D01*
X-1111220Y-473560D01*
X-1111720Y-473240D01*
X-1113240Y-471720D01*
X-1113560Y-471240D01*
X-1113760Y-470660D01*
X-1114140Y-469980D01*
X-1114320Y-469120D01*
X-1114500Y-468680D01*
Y-464980D01*
X-1114320Y-464260D01*
X-1114140Y-463720D01*
X-1113940Y-463320D01*
X-1113720Y-462660D01*
X-1113560Y-462000D01*
X-1111880Y-460320D01*
X-1112540Y-460460D01*
G01X-1099300Y-466400D02*
X-1093800Y-464400D01*
X-1093900Y-461100D01*
X-1094800Y-459000D01*
X-1096800Y-457300D01*
X-1100000Y-456100D01*
X-1102800Y-455900D01*
X-1106300Y-456300D01*
X-1109600Y-458100D01*
X-1111400Y-460500D01*
X-1112900Y-462600D01*
X-1113600Y-465600D01*
X-1113500Y-469100D01*
X-1112100Y-471900D01*
X-1109600Y-473300D01*
X-1105700Y-473800D01*
X-1101000Y-473400D01*
X-1098200Y-471800D01*
X-1096600Y-470100D01*
X-1096000Y-469500D01*
X-1100800Y-469700D01*
X-1102300Y-471100D01*
X-1097900Y-470400D01*
X-1100300Y-471800D01*
X-1103200Y-471400D01*
X-1100600Y-472600D01*
X-1103000D01*
X-1103700Y-471900D01*
X-1103400Y-473000D01*
X-1104600Y-471900D01*
X-1106200D01*
X-1104100Y-473100D01*
X-1107200Y-472700D01*
X-1110100Y-472100D01*
X-1111500Y-470900D01*
X-1112600Y-468600D01*
X-1112700Y-466000D01*
X-1112400Y-463700D01*
X-1111400Y-461600D01*
X-1109600Y-459500D01*
X-1108100Y-458200D01*
X-1105900Y-457200D01*
X-1102200Y-456700D01*
X-1099600Y-457300D01*
X-1097000Y-458400D01*
X-1095500Y-459500D01*
X-1094600Y-461900D01*
X-1094500Y-463900D01*
X-1098800Y-465200D01*
X-1098600Y-464000D01*
X-1095100Y-463100D01*
X-1095300Y-462000D01*
X-1098500Y-463000D01*
X-1098600Y-461700D01*
X-1095600Y-461300D01*
X-1095900Y-460200D01*
X-1098400Y-460700D01*
X-1098900Y-459900D01*
X-1096600Y-459400D01*
X-1097100Y-458900D01*
X-1099400Y-459000D01*
X-1098800Y-458500D01*
X-1100600Y-458000D01*
X-1102400Y-457400D01*
X-1104200Y-457500D01*
X-1106200Y-458100D01*
X-1107900Y-459000D01*
X-1110500Y-462200D01*
X-1111800Y-464800D01*
Y-467700D01*
X-1110700Y-470300D01*
X-1108700Y-472000D01*
X-1106600Y-471900D01*
X-1107900Y-470300D01*
X-1108900Y-468700D01*
Y-465500D01*
X-1107900Y-462300D01*
X-1106500Y-459900D01*
X-1104100Y-458200D01*
X-1108000Y-460000D01*
X-1108100Y-461500D01*
X-1108700Y-461200D01*
X-1110300Y-463600D01*
X-1111000Y-466000D01*
X-1110700Y-468100D01*
X-1109500Y-470600D01*
X-1107700Y-471400D01*
X-1109300Y-469100D01*
X-1109800Y-467600D01*
X-1108600Y-462200D01*
X-1110400Y-466800D01*
G01X-1113600Y-460900D02*
X-1112100Y-459000D01*
G01X-1093100Y-469400D02*
X-1087900Y-469700D01*
X-1086500Y-471400D01*
X-1083400Y-472300D01*
X-1081000Y-472000D01*
X-1079300Y-470600D01*
X-1079000Y-468900D01*
X-1079500Y-467700D01*
X-1080300Y-466600D01*
X-1081800Y-466000D01*
X-1083300Y-465500D01*
X-1085300Y-465000D01*
X-1087900Y-464000D01*
X-1089100Y-463200D01*
X-1089800Y-461000D01*
X-1089500Y-459000D01*
X-1088600Y-457700D01*
X-1086500Y-456700D01*
X-1084600Y-456100D01*
X-1081900Y-455900D01*
X-1079900Y-455800D01*
X-1076900Y-456300D01*
X-1075000Y-457000D01*
X-1073700Y-458000D01*
X-1073300Y-459400D01*
X-1077600Y-459500D01*
X-1078100Y-458800D01*
X-1074300Y-458500D01*
X-1074600Y-457800D01*
X-1078200Y-458200D01*
X-1076000Y-457400D01*
X-1079100Y-457700D01*
X-1077100Y-456900D01*
X-1080100Y-457300D01*
X-1079200Y-456600D01*
X-1083100Y-456800D01*
X-1080600Y-457300D01*
X-1083400Y-457700D01*
X-1083600Y-457000D01*
X-1087900Y-458400D01*
X-1084000Y-458100D01*
X-1088600Y-459100D01*
X-1088800Y-461500D01*
X-1087700Y-463600D01*
X-1084400Y-464300D01*
X-1081200Y-465400D01*
X-1078800Y-467300D01*
X-1078300Y-470500D01*
X-1079900Y-472600D01*
X-1083500Y-473300D01*
X-1085600Y-472600D01*
X-1088800Y-470500D01*
X-1092600Y-470200D01*
X-1092100Y-471800D01*
X-1091700Y-471300D01*
X-1089300Y-471500D01*
X-1091300Y-472300D01*
X-1088700Y-471600D01*
X-1084000Y-473500D01*
X-1089100D01*
X-1091000Y-472900D01*
X-1087200Y-472800D01*
X-1082700Y-473700D01*
X-1079000Y-473600D01*
X-1076500Y-472300D01*
X-1074700Y-470600D01*
X-1074300Y-467300D01*
X-1074800Y-465300D01*
X-1078800Y-463600D01*
X-1081600Y-462900D01*
X-1083400Y-462500D01*
X-1084800Y-461500D01*
X-1085000Y-458900D01*
X-1088100Y-459800D01*
X-1087200Y-462700D01*
X-1085000Y-463400D01*
X-1082000Y-464100D01*
X-1079600Y-465100D01*
X-1078200Y-466500D01*
X-1077700Y-468500D01*
X-1077500Y-470100D01*
X-1079200Y-472800D01*
X-1076800Y-471400D01*
X-1075300Y-470000D01*
X-1077300Y-470900D01*
X-1075000Y-468800D01*
X-1075200Y-466100D01*
X-1082700Y-462700D01*
X-1084200Y-462900D01*
X-1086600Y-461800D01*
X-1087200Y-460300D01*
X-1085800Y-459800D01*
X-1086600Y-461000D01*
X-1085300Y-460400D01*
X-1085600Y-461400D01*
X-1076700Y-466500D01*
X-1075900Y-467100D01*
X-1075700Y-468400D01*
X-1076800Y-469500D01*
X-1077800Y-466200D01*
X-1075900Y-468800D01*
G01X-1093780Y-468700D02*
X-1087100D01*
Y-469740D01*
X-1086800Y-470060D01*
X-1086520Y-470600D01*
X-1085820Y-470820D01*
X-1085660Y-471000D01*
X-1085120Y-471260D01*
X-1084400Y-471500D01*
X-1082360D01*
X-1080540Y-470600D01*
X-1080100Y-470140D01*
Y-469780D01*
X-1079840Y-469380D01*
X-1080380Y-467740D01*
X-1081440Y-466940D01*
X-1082560Y-466720D01*
X-1085740Y-465920D01*
X-1086940Y-465520D01*
X-1087600Y-465360D01*
X-1087740Y-465200D01*
X-1088540Y-464800D01*
X-1089140Y-464200D01*
X-1089540Y-464000D01*
X-1089800Y-463740D01*
X-1090000Y-463340D01*
X-1090180Y-463180D01*
X-1090500Y-462200D01*
Y-459800D01*
X-1090320Y-459260D01*
X-1090140Y-458500D01*
X-1090000Y-458260D01*
X-1089000Y-457260D01*
X-1088860Y-456940D01*
X-1085920Y-455480D01*
X-1083620Y-455100D01*
X-1082060Y-454900D01*
X-1080520D01*
X-1078580Y-455100D01*
X-1076240Y-455480D01*
X-1075120Y-455860D01*
X-1074800Y-456020D01*
X-1073680Y-456760D01*
X-1073160Y-457300D01*
X-1072620Y-458020D01*
X-1072500Y-458240D01*
Y-460300D01*
X-1078500D01*
Y-459200D01*
X-1079580Y-458380D01*
X-1080160Y-458100D01*
X-1082380D01*
X-1083280Y-458360D01*
X-1084020Y-458940D01*
X-1084340Y-459900D01*
X-1084060Y-460720D01*
X-1083740Y-461340D01*
X-1081860Y-462280D01*
X-1079400Y-462500D01*
X-1078660Y-462680D01*
X-1078100Y-462860D01*
X-1076500Y-463460D01*
X-1075320Y-463860D01*
X-1075060Y-464000D01*
X-1073820Y-465220D01*
X-1073480Y-466260D01*
X-1073300Y-467160D01*
Y-468420D01*
X-1073860Y-470700D01*
X-1074000Y-470960D01*
X-1075140Y-472300D01*
X-1075280Y-472440D01*
X-1076600Y-473380D01*
X-1077320Y-473740D01*
X-1079600Y-474500D01*
X-1088240D01*
X-1089160Y-474320D01*
X-1089920Y-474120D01*
X-1090860Y-473760D01*
X-1091560Y-473400D01*
X-1092700Y-472460D01*
X-1093180Y-471980D01*
X-1093340Y-471480D01*
X-1093520Y-471100D01*
X-1093700Y-470320D01*
X-1093780Y-468700D01*
G01X-1095100D02*
X-1092800D01*
G01X-1058300Y-469400D02*
X-1055400Y-467100D01*
X-1053900Y-463700D01*
X-1054400Y-461200D01*
X-1055900Y-459900D01*
X-1054800Y-463500D01*
X-1055400Y-463600D01*
X-1054600Y-464500D01*
X-1055700D01*
X-1055400Y-465300D01*
X-1056200Y-466800D01*
G01X-1059300Y-457700D02*
X-1059100Y-455600D01*
X-1055200Y-456300D01*
X-1052700Y-457900D01*
X-1051100Y-460800D01*
X-1050900Y-465200D01*
X-1052900Y-469400D01*
X-1055300Y-471900D01*
X-1059000Y-473500D01*
X-1066000D01*
X-1068000Y-471900D01*
X-1070200Y-468700D01*
X-1070600Y-464500D01*
X-1069000Y-460500D01*
X-1066000Y-457500D01*
X-1063000Y-456500D01*
X-1059200Y-456000D01*
X-1053000Y-458500D01*
X-1052000Y-461500D01*
Y-465700D01*
X-1053400Y-468600D01*
X-1055700Y-471000D01*
X-1058900Y-472600D01*
X-1063700Y-473000D01*
X-1065900Y-473600D01*
X-1068300Y-472900D01*
X-1070600Y-469300D01*
X-1065100Y-472600D01*
X-1060800Y-472200D01*
X-1057200Y-470700D01*
X-1055200Y-469100D01*
X-1053300Y-466500D01*
X-1052500Y-463400D01*
X-1052900Y-460100D01*
X-1057000Y-457400D01*
X-1058700Y-457200D01*
X-1057000Y-458500D01*
X-1055100Y-459800D01*
X-1053800Y-460900D01*
X-1053400Y-463100D01*
X-1053600Y-465600D01*
X-1054800Y-467500D01*
X-1056400Y-469200D01*
X-1058500Y-470200D01*
X-1060200Y-470700D01*
X-1061500Y-471400D01*
X-1063300Y-471600D01*
X-1065400Y-471500D01*
X-1069000Y-469300D01*
X-1069600Y-466400D01*
X-1069700Y-463700D01*
X-1068600Y-461200D01*
X-1066700Y-459200D01*
X-1063900Y-457600D01*
X-1061100Y-457000D01*
X-1059600D01*
X-1060200Y-457500D01*
X-1063300Y-458000D01*
X-1065300Y-459500D01*
X-1066900Y-460600D01*
X-1067900Y-462100D01*
X-1068800Y-464300D01*
X-1068700Y-466900D01*
X-1068200Y-469100D01*
X-1066900Y-470200D01*
X-1064300Y-470900D01*
X-1065700Y-469300D01*
X-1065800Y-465900D01*
X-1065300Y-462900D01*
X-1061200Y-458200D01*
X-1063600Y-458900D01*
X-1066400Y-461300D01*
X-1067800Y-464200D01*
Y-467200D01*
X-1067400Y-469300D01*
X-1066300Y-469700D01*
X-1067100Y-466400D01*
X-1066600Y-463400D01*
X-1064700Y-460000D01*
X-1062600Y-458800D01*
X-1065300Y-461700D01*
X-1066700Y-467400D01*
G01X-1060840Y-455100D02*
X-1057160D01*
X-1055260Y-455480D01*
X-1054740Y-455640D01*
X-1053380Y-456420D01*
X-1052660Y-456800D01*
X-1052020Y-457420D01*
X-1051820Y-458020D01*
X-1051200Y-458660D01*
X-1051000Y-459060D01*
X-1050840Y-459200D01*
X-1050700Y-459780D01*
Y-460140D01*
X-1050400Y-460460D01*
X-1050280Y-460680D01*
X-1050100Y-461740D01*
Y-464240D01*
X-1050280Y-465160D01*
X-1050480Y-465980D01*
X-1050680Y-467120D01*
X-1051220Y-468180D01*
X-1051840Y-469020D01*
X-1052040Y-469600D01*
X-1052740Y-470500D01*
X-1054480Y-472240D01*
X-1055000Y-472580D01*
X-1055420Y-472780D01*
X-1056220Y-473380D01*
X-1056920Y-473740D01*
X-1059380Y-474500D01*
X-1065600D01*
X-1067860Y-473740D01*
X-1068160Y-473600D01*
X-1069500Y-472460D01*
X-1069820Y-472120D01*
X-1070380Y-471200D01*
X-1071140Y-469860D01*
X-1071300Y-469400D01*
Y-464580D01*
X-1071120Y-463880D01*
X-1070740Y-462900D01*
X-1070540Y-462320D01*
X-1069980Y-461000D01*
X-1068840Y-459500D01*
X-1066900Y-457560D01*
X-1066180Y-457020D01*
X-1065400Y-456620D01*
X-1064440Y-456040D01*
X-1063500Y-455660D01*
X-1062940Y-455480D01*
X-1060840Y-455100D01*
G01X-1057800Y-458580D02*
X-1057000Y-459120D01*
X-1056760Y-459840D01*
X-1056340Y-460460D01*
X-1056100Y-461640D01*
Y-463760D01*
X-1056320Y-464860D01*
X-1056720Y-466060D01*
X-1056940Y-466920D01*
X-1057200Y-467460D01*
X-1057640Y-467880D01*
X-1058040Y-468480D01*
X-1059960Y-470420D01*
X-1061020Y-470840D01*
X-1061420Y-471100D01*
X-1062720D01*
X-1063340Y-470840D01*
X-1063860Y-470600D01*
X-1064360Y-470080D01*
X-1064820Y-469400D01*
X-1065100Y-468840D01*
Y-464920D01*
X-1064880Y-464120D01*
X-1064420Y-462780D01*
X-1064160Y-462520D01*
X-1063620Y-461700D01*
X-1063200Y-460840D01*
X-1062500Y-460140D01*
X-1062120Y-459860D01*
X-1061720Y-459360D01*
X-1060600Y-458580D01*
X-1060040Y-458300D01*
X-1058360D01*
X-1057800Y-458580D01*
G01X-1040300Y-459100D02*
X-1041400Y-464800D01*
G01X-1044800Y-458200D02*
X-1041400D01*
X-1044300Y-472700D01*
X-1047400Y-472300D01*
X-1044100Y-458800D01*
X-1042400Y-459100D01*
X-1045100Y-471900D01*
X-1046500D01*
X-1043400Y-459700D01*
X-1045600Y-471500D01*
G01X-1036600Y-449900D02*
X-1036800Y-451300D01*
X-1038600Y-452400D01*
X-1039800Y-456100D01*
X-1033700Y-456500D01*
X-1032300Y-452100D01*
X-1028400Y-452000D01*
X-1028900Y-455400D01*
X-1027200Y-456600D01*
X-1025900Y-456800D01*
X-1026200Y-458200D01*
X-1030000Y-458400D01*
X-1031800Y-468900D01*
X-1030400Y-471700D01*
X-1029400D01*
X-1029600Y-473300D01*
X-1033100Y-473400D01*
X-1036100Y-472800D01*
X-1036200Y-470500D01*
X-1035900Y-467100D01*
X-1034400Y-461400D01*
X-1033800Y-458800D01*
X-1033500Y-458400D01*
X-1035000Y-458200D01*
X-1039600D01*
X-1040800Y-458300D01*
X-1043600Y-473200D01*
X-1048000Y-473000D01*
X-1045100Y-459400D01*
X-1044900Y-458400D01*
X-1048700D01*
X-1048100Y-456600D01*
X-1044900Y-456400D01*
X-1045200Y-457700D01*
X-1047600Y-457500D01*
X-1026500D01*
G01X-1049580Y-459100D02*
X-1048740Y-455700D01*
X-1044900D01*
Y-454780D01*
X-1044720Y-454060D01*
X-1044340Y-452920D01*
X-1043940Y-452120D01*
X-1043740Y-451520D01*
X-1043600Y-451260D01*
X-1042340Y-450000D01*
X-1042080Y-449860D01*
X-1040580Y-449480D01*
X-1039440Y-449300D01*
X-1036140D01*
X-1035440Y-449400D01*
X-1035480Y-449540D01*
X-1035680Y-450360D01*
X-1035880Y-451280D01*
X-1036000Y-451900D01*
X-1036740D01*
X-1037060Y-452200D01*
X-1037860Y-452600D01*
X-1038220Y-452980D01*
X-1038480Y-453740D01*
X-1038960Y-455700D01*
X-1034020D01*
X-1033720Y-455080D01*
X-1033500Y-453400D01*
X-1032940Y-451100D01*
X-1027260D01*
X-1027280Y-451180D01*
X-1027480Y-452780D01*
X-1027860Y-454280D01*
X-1028100Y-454760D01*
Y-455700D01*
X-1024800D01*
X-1024880Y-455940D01*
X-1025080Y-456940D01*
X-1025280Y-457540D01*
X-1025480Y-458560D01*
X-1025620Y-459100D01*
X-1029100D01*
Y-460000D01*
X-1029280Y-460540D01*
X-1029480Y-461540D01*
X-1029680Y-462140D01*
X-1029880Y-462960D01*
X-1030100Y-464000D01*
X-1030280Y-465560D01*
X-1030480Y-466140D01*
X-1030680Y-467140D01*
X-1030880Y-467740D01*
X-1031040Y-468400D01*
X-1031300Y-468660D01*
Y-469800D01*
X-1030300Y-470560D01*
X-1029940Y-470900D01*
X-1028220D01*
X-1028680Y-472780D01*
X-1028880Y-474120D01*
Y-474140D01*
X-1030720Y-474300D01*
X-1032860D01*
X-1034380Y-474120D01*
X-1035860Y-473740D01*
X-1036640Y-473280D01*
X-1036960Y-472660D01*
X-1037100Y-472280D01*
Y-470160D01*
X-1036920Y-469260D01*
X-1036700Y-468640D01*
X-1036500Y-466840D01*
X-1036320Y-466260D01*
X-1036120Y-465260D01*
X-1035920Y-464660D01*
X-1035720Y-463660D01*
X-1035520Y-463060D01*
X-1035320Y-462060D01*
X-1035120Y-461440D01*
X-1034820Y-459100D01*
X-1039900D01*
Y-460220D01*
X-1040280Y-461780D01*
X-1040480Y-463380D01*
X-1041280Y-466540D01*
X-1041480Y-467140D01*
X-1041700Y-468200D01*
X-1041880Y-469760D01*
X-1042080Y-470340D01*
X-1042280Y-471360D01*
X-1042480Y-472140D01*
X-1042680Y-472740D01*
X-1042880Y-473740D01*
X-1042940Y-473900D01*
X-1049140D01*
X-1048300Y-470620D01*
X-1048100Y-469020D01*
X-1047920Y-468260D01*
X-1047720Y-467660D01*
X-1047520Y-466660D01*
X-1047320Y-466060D01*
X-1047120Y-465060D01*
X-1046920Y-464460D01*
X-1046700Y-463400D01*
X-1046500Y-462020D01*
X-1046140Y-460500D01*
X-1045900Y-460040D01*
Y-459100D01*
X-1049580D01*
G01X-1038400Y-451100D02*
X-1040600Y-455800D01*
X-1043300D01*
X-1041400Y-451300D01*
X-1038900Y-451000D01*
X-1041200Y-455000D01*
X-1042000Y-455100D01*
X-1040500Y-452000D01*
G01X-1037500Y-449800D02*
X-1037800Y-451000D01*
X-1038500Y-450100D01*
X-1042000Y-450700D01*
X-1043100Y-452300D01*
X-1044100Y-455100D01*
X-1044200Y-456600D01*
X-1036600Y-456800D01*
G01X-1031100Y-472500D02*
X-1031400Y-470900D01*
X-1031900Y-472200D01*
X-1035200D01*
Y-467600D01*
X-1032000Y-453700D01*
X-1030500Y-453800D01*
X-1030000Y-456700D01*
X-1033400Y-471900D01*
X-1034300Y-471600D01*
X-1034200Y-467100D01*
X-1031400Y-454500D01*
X-1030700Y-456500D01*
X-1033700Y-470600D01*
X-1032700Y-461100D01*
G01X-1032000Y-452900D02*
X-1029300D01*
X-1028000Y-457000D01*
X-1029500Y-453600D01*
X-1029100Y-457300D01*
X-1032800Y-472800D01*
X-1030200Y-472600D01*
M02*
